(kicad_sch
	(version 20250114)
	(generator "eeschema")
	(generator_version "9.0")
	(paper "A3")
	(title_block
		(title "COM Express 7 Baseboard")
		(date "2025-02-04")
		(rev "1.1.2")
		(company "Antmicro Ltd")
		(comment 1 "www.antmicro.com")
	)
	(bus_alias "I2C"
		(members "SDA" "SCL" "~{INT}")
	)
	(text "For REFCLK\nSee PCI Express\nOCuLink\nSpecification\nRevision 1.0\nTable 2-2 note 2"
		(exclude_from_sim no)
		(at 260.35 123.19 0)
		(effects
			(font
				(size 1.27 1.27)
			)
			(justify left bottom)
		)
	)
	(text "OCuLink"
		(exclude_from_sim no)
		(at 208.534 72.644 0)
		(effects
			(font
				(size 2 2)
				(thickness 0.4)
				(bold yes)
			)
			(justify left bottom)
		)
	)
	(junction
		(at 210.82 92.71)
		(diameter 0)
		(color 0 0 0 0)
	)
	(junction
		(at 214.63 90.17)
		(diameter 0)
		(color 0 0 0 0)
	)
	(junction
		(at 194.31 92.71)
		(diameter 0)
		(color 0 0 0 0)
	)
	(junction
		(at 194.31 124.46)
		(diameter 0)
		(color 0 0 0 0)
	)
	(junction
		(at 264.16 190.5)
		(diameter 0)
		(color 0 0 0 0)
	)
	(junction
		(at 194.31 90.17)
		(diameter 0)
		(color 0 0 0 0)
	)
	(junction
		(at 231.14 87.63)
		(diameter 0)
		(color 0 0 0 0)
	)
	(junction
		(at 215.9 104.14)
		(diameter 0)
		(color 0 0 0 0)
	)
	(junction
		(at 194.31 97.79)
		(diameter 0)
		(color 0 0 0 0)
	)
	(junction
		(at 198.12 127)
		(diameter 0)
		(color 0 0 0 0)
	)
	(junction
		(at 218.44 90.17)
		(diameter 0)
		(color 0 0 0 0)
	)
	(no_connect
		(at 373.38 139.7)
	)
	(no_connect
		(at 373.38 142.24)
	)
	(no_connect
		(at 237.49 129.54)
	)
	(bus_entry
		(at 208.28 109.22)
		(size -1.27 -1.27)
		(stroke
			(width 0)
			(type default)
		)
	)
	(bus_entry
		(at 179.07 143.51)
		(size 1.27 1.27)
		(stroke
			(width 0)
			(type default)
		)
	)
	(bus_entry
		(at 208.28 111.76)
		(size -1.27 -1.27)
		(stroke
			(width 0)
			(type default)
		)
	)
	(bus_entry
		(at 176.53 116.84)
		(size -1.27 -1.27)
		(stroke
			(width 0)
			(type default)
		)
	)
	(bus_entry
		(at 179.07 166.37)
		(size 1.27 1.27)
		(stroke
			(width 0)
			(type default)
		)
	)
	(bus_entry
		(at 179.07 179.07)
		(size 1.27 1.27)
		(stroke
			(width 0)
			(type default)
		)
	)
	(bus_entry
		(at 179.07 135.89)
		(size 1.27 1.27)
		(stroke
			(width 0)
			(type default)
		)
	)
	(bus_entry
		(at 179.07 186.69)
		(size 1.27 1.27)
		(stroke
			(width 0)
			(type default)
		)
	)
	(bus_entry
		(at 179.07 151.13)
		(size 1.27 1.27)
		(stroke
			(width 0)
			(type default)
		)
	)
	(bus_entry
		(at 179.07 163.83)
		(size 1.27 1.27)
		(stroke
			(width 0)
			(type default)
		)
	)
	(bus_entry
		(at 176.53 119.38)
		(size -1.27 -1.27)
		(stroke
			(width 0)
			(type default)
		)
	)
	(bus_entry
		(at 179.07 173.99)
		(size 1.27 1.27)
		(stroke
			(width 0)
			(type default)
		)
	)
	(bus_entry
		(at 179.07 133.35)
		(size 1.27 1.27)
		(stroke
			(width 0)
			(type default)
		)
	)
	(bus_entry
		(at 179.07 140.97)
		(size 1.27 1.27)
		(stroke
			(width 0)
			(type default)
		)
	)
	(bus_entry
		(at 179.07 181.61)
		(size 1.27 1.27)
		(stroke
			(width 0)
			(type default)
		)
	)
	(bus_entry
		(at 179.07 148.59)
		(size 1.27 1.27)
		(stroke
			(width 0)
			(type default)
		)
	)
	(bus_entry
		(at 179.07 171.45)
		(size 1.27 1.27)
		(stroke
			(width 0)
			(type default)
		)
	)
	(bus_entry
		(at 179.07 156.21)
		(size 1.27 1.27)
		(stroke
			(width 0)
			(type default)
		)
	)
	(bus_entry
		(at 179.07 189.23)
		(size 1.27 1.27)
		(stroke
			(width 0)
			(type default)
		)
	)
	(bus_entry
		(at 179.07 158.75)
		(size 1.27 1.27)
		(stroke
			(width 0)
			(type default)
		)
	)
	(wire
		(pts
			(xy 223.52 90.17) (xy 218.44 90.17)
		)
		(stroke
			(width 0)
			(type default)
		)
	)
	(wire
		(pts
			(xy 271.78 158.75) (xy 287.02 158.75)
		)
		(stroke
			(width 0)
			(type default)
		)
	)
	(wire
		(pts
			(xy 271.78 134.62) (xy 287.02 134.62)
		)
		(stroke
			(width 0)
			(type default)
		)
	)
	(wire
		(pts
			(xy 176.53 119.38) (xy 237.49 119.38)
		)
		(stroke
			(width 0)
			(type default)
		)
	)
	(bus
		(pts
			(xy 171.45 129.54) (xy 177.8 129.54)
		)
		(stroke
			(width 0)
			(type default)
		)
	)
	(wire
		(pts
			(xy 285.75 146.05) (xy 285.75 144.78)
		)
		(stroke
			(width 0)
			(type default)
		)
	)
	(wire
		(pts
			(xy 194.31 90.17) (xy 194.31 92.71)
		)
		(stroke
			(width 0)
			(type default)
		)
	)
	(wire
		(pts
			(xy 271.78 153.67) (xy 287.02 153.67)
		)
		(stroke
			(width 0)
			(type default)
		)
	)
	(wire
		(pts
			(xy 198.12 127) (xy 237.49 127)
		)
		(stroke
			(width 0)
			(type default)
		)
	)
	(wire
		(pts
			(xy 285.75 163.83) (xy 287.02 163.83)
		)
		(stroke
			(width 0)
			(type default)
		)
	)
	(wire
		(pts
			(xy 180.34 172.72) (xy 237.49 172.72)
		)
		(stroke
			(width 0)
			(type default)
		)
	)
	(wire
		(pts
			(xy 264.16 190.5) (xy 264.16 191.77)
		)
		(stroke
			(width 0)
			(type default)
		)
	)
	(bus
		(pts
			(xy 179.07 158.75) (xy 179.07 163.83)
		)
		(stroke
			(width 0)
			(type default)
		)
	)
	(wire
		(pts
			(xy 328.93 144.78) (xy 330.2 144.78)
		)
		(stroke
			(width 0)
			(type default)
		)
	)
	(bus
		(pts
			(xy 175.26 113.03) (xy 173.99 111.76)
		)
		(stroke
			(width 0)
			(type default)
		)
	)
	(wire
		(pts
			(xy 194.31 88.9) (xy 194.31 90.17)
		)
		(stroke
			(width 0)
			(type default)
		)
	)
	(wire
		(pts
			(xy 237.49 104.14) (xy 215.9 104.14)
		)
		(stroke
			(width 0)
			(type default)
		)
	)
	(bus
		(pts
			(xy 179.07 173.99) (xy 179.07 179.07)
		)
		(stroke
			(width 0)
			(type default)
		)
	)
	(bus
		(pts
			(xy 179.07 133.35) (xy 179.07 135.89)
		)
		(stroke
			(width 0)
			(type default)
		)
	)
	(wire
		(pts
			(xy 358.14 158.75) (xy 373.38 158.75)
		)
		(stroke
			(width 0)
			(type default)
		)
	)
	(wire
		(pts
			(xy 190.5 127) (xy 198.12 127)
		)
		(stroke
			(width 0)
			(type default)
		)
	)
	(bus
		(pts
			(xy 179.07 143.51) (xy 179.07 148.59)
		)
		(stroke
			(width 0)
			(type default)
		)
	)
	(wire
		(pts
			(xy 358.14 137.16) (xy 373.38 137.16)
		)
		(stroke
			(width 0)
			(type default)
		)
	)
	(wire
		(pts
			(xy 194.31 97.79) (xy 194.31 100.33)
		)
		(stroke
			(width 0)
			(type default)
		)
	)
	(bus
		(pts
			(xy 175.26 118.11) (xy 175.26 115.57)
		)
		(stroke
			(width 0)
			(type default)
		)
	)
	(wire
		(pts
			(xy 198.12 105.41) (xy 198.12 127)
		)
		(stroke
			(width 0)
			(type default)
		)
	)
	(wire
		(pts
			(xy 358.14 156.21) (xy 373.38 156.21)
		)
		(stroke
			(width 0)
			(type default)
		)
	)
	(wire
		(pts
			(xy 271.78 142.24) (xy 287.02 142.24)
		)
		(stroke
			(width 0)
			(type default)
		)
	)
	(bus
		(pts
			(xy 179.07 171.45) (xy 179.07 173.99)
		)
		(stroke
			(width 0)
			(type default)
		)
	)
	(wire
		(pts
			(xy 223.52 90.17) (xy 223.52 101.6)
		)
		(stroke
			(width 0)
			(type default)
		)
	)
	(wire
		(pts
			(xy 271.78 139.7) (xy 287.02 139.7)
		)
		(stroke
			(width 0)
			(type default)
		)
	)
	(wire
		(pts
			(xy 285.75 165.1) (xy 285.75 163.83)
		)
		(stroke
			(width 0)
			(type default)
		)
	)
	(wire
		(pts
			(xy 285.75 144.78) (xy 287.02 144.78)
		)
		(stroke
			(width 0)
			(type default)
		)
	)
	(wire
		(pts
			(xy 264.16 187.96) (xy 264.16 190.5)
		)
		(stroke
			(width 0)
			(type default)
		)
	)
	(bus
		(pts
			(xy 179.07 148.59) (xy 179.07 151.13)
		)
		(stroke
			(width 0)
			(type default)
		)
	)
	(wire
		(pts
			(xy 224.79 111.76) (xy 237.49 111.76)
		)
		(stroke
			(width 0)
			(type default)
		)
	)
	(wire
		(pts
			(xy 198.12 97.79) (xy 194.31 97.79)
		)
		(stroke
			(width 0)
			(type default)
		)
	)
	(bus
		(pts
			(xy 179.07 135.89) (xy 179.07 140.97)
		)
		(stroke
			(width 0)
			(type default)
		)
	)
	(bus
		(pts
			(xy 207.01 107.95) (xy 207.01 110.49)
		)
		(stroke
			(width 0)
			(type default)
		)
	)
	(wire
		(pts
			(xy 372.11 144.78) (xy 373.38 144.78)
		)
		(stroke
			(width 0)
			(type default)
		)
	)
	(wire
		(pts
			(xy 358.14 134.62) (xy 373.38 134.62)
		)
		(stroke
			(width 0)
			(type default)
		)
	)
	(wire
		(pts
			(xy 218.44 90.17) (xy 218.44 93.98)
		)
		(stroke
			(width 0)
			(type default)
		)
	)
	(wire
		(pts
			(xy 358.14 161.29) (xy 373.38 161.29)
		)
		(stroke
			(width 0)
			(type default)
		)
	)
	(wire
		(pts
			(xy 314.96 142.24) (xy 330.2 142.24)
		)
		(stroke
			(width 0)
			(type default)
		)
	)
	(wire
		(pts
			(xy 209.55 92.71) (xy 210.82 92.71)
		)
		(stroke
			(width 0)
			(type default)
		)
	)
	(wire
		(pts
			(xy 180.34 175.26) (xy 237.49 175.26)
		)
		(stroke
			(width 0)
			(type default)
		)
	)
	(wire
		(pts
			(xy 237.49 142.24) (xy 180.34 142.24)
		)
		(stroke
			(width 0)
			(type default)
		)
	)
	(wire
		(pts
			(xy 194.31 90.17) (xy 204.47 90.17)
		)
		(stroke
			(width 0)
			(type default)
		)
	)
	(wire
		(pts
			(xy 271.78 161.29) (xy 287.02 161.29)
		)
		(stroke
			(width 0)
			(type default)
		)
	)
	(wire
		(pts
			(xy 262.89 190.5) (xy 264.16 190.5)
		)
		(stroke
			(width 0)
			(type default)
		)
	)
	(bus
		(pts
			(xy 179.07 130.81) (xy 179.07 133.35)
		)
		(stroke
			(width 0)
			(type default)
		)
	)
	(wire
		(pts
			(xy 210.82 92.71) (xy 210.82 93.98)
		)
		(stroke
			(width 0)
			(type default)
		)
	)
	(bus
		(pts
			(xy 179.07 130.81) (xy 177.8 129.54)
		)
		(stroke
			(width 0)
			(type default)
		)
	)
	(wire
		(pts
			(xy 358.14 153.67) (xy 373.38 153.67)
		)
		(stroke
			(width 0)
			(type default)
		)
	)
	(wire
		(pts
			(xy 372.11 163.83) (xy 373.38 163.83)
		)
		(stroke
			(width 0)
			(type default)
		)
	)
	(wire
		(pts
			(xy 180.34 182.88) (xy 237.49 182.88)
		)
		(stroke
			(width 0)
			(type default)
		)
	)
	(wire
		(pts
			(xy 180.34 167.64) (xy 237.49 167.64)
		)
		(stroke
			(width 0)
			(type default)
		)
	)
	(bus
		(pts
			(xy 179.07 140.97) (xy 179.07 143.51)
		)
		(stroke
			(width 0)
			(type default)
		)
	)
	(wire
		(pts
			(xy 214.63 88.9) (xy 214.63 90.17)
		)
		(stroke
			(width 0)
			(type default)
		)
	)
	(wire
		(pts
			(xy 180.34 165.1) (xy 237.49 165.1)
		)
		(stroke
			(width 0)
			(type default)
		)
	)
	(bus
		(pts
			(xy 179.07 156.21) (xy 179.07 158.75)
		)
		(stroke
			(width 0)
			(type default)
		)
	)
	(bus
		(pts
			(xy 179.07 186.69) (xy 179.07 189.23)
		)
		(stroke
			(width 0)
			(type default)
		)
	)
	(wire
		(pts
			(xy 180.34 190.5) (xy 237.49 190.5)
		)
		(stroke
			(width 0)
			(type default)
		)
	)
	(wire
		(pts
			(xy 171.45 127) (xy 185.42 127)
		)
		(stroke
			(width 0)
			(type default)
		)
	)
	(wire
		(pts
			(xy 314.96 158.75) (xy 330.2 158.75)
		)
		(stroke
			(width 0)
			(type default)
		)
	)
	(wire
		(pts
			(xy 215.9 104.14) (xy 215.9 92.71)
		)
		(stroke
			(width 0)
			(type default)
		)
	)
	(wire
		(pts
			(xy 237.49 99.06) (xy 236.22 99.06)
		)
		(stroke
			(width 0)
			(type default)
		)
	)
	(wire
		(pts
			(xy 215.9 92.71) (xy 210.82 92.71)
		)
		(stroke
			(width 0)
			(type default)
		)
	)
	(wire
		(pts
			(xy 237.49 149.86) (xy 180.34 149.86)
		)
		(stroke
			(width 0)
			(type default)
		)
	)
	(wire
		(pts
			(xy 171.45 124.46) (xy 185.42 124.46)
		)
		(stroke
			(width 0)
			(type default)
		)
	)
	(wire
		(pts
			(xy 237.49 144.78) (xy 180.34 144.78)
		)
		(stroke
			(width 0)
			(type default)
		)
	)
	(wire
		(pts
			(xy 190.5 124.46) (xy 194.31 124.46)
		)
		(stroke
			(width 0)
			(type default)
		)
	)
	(wire
		(pts
			(xy 237.49 160.02) (xy 180.34 160.02)
		)
		(stroke
			(width 0)
			(type default)
		)
	)
	(wire
		(pts
			(xy 194.31 92.71) (xy 204.47 92.71)
		)
		(stroke
			(width 0)
			(type default)
		)
	)
	(wire
		(pts
			(xy 237.49 152.4) (xy 180.34 152.4)
		)
		(stroke
			(width 0)
			(type default)
		)
	)
	(wire
		(pts
			(xy 372.11 165.1) (xy 372.11 163.83)
		)
		(stroke
			(width 0)
			(type default)
		)
	)
	(bus
		(pts
			(xy 179.07 151.13) (xy 179.07 156.21)
		)
		(stroke
			(width 0)
			(type default)
		)
	)
	(bus
		(pts
			(xy 179.07 179.07) (xy 179.07 181.61)
		)
		(stroke
			(width 0)
			(type default)
		)
	)
	(wire
		(pts
			(xy 209.55 90.17) (xy 214.63 90.17)
		)
		(stroke
			(width 0)
			(type default)
		)
	)
	(wire
		(pts
			(xy 314.96 134.62) (xy 330.2 134.62)
		)
		(stroke
			(width 0)
			(type default)
		)
	)
	(wire
		(pts
			(xy 314.96 161.29) (xy 330.2 161.29)
		)
		(stroke
			(width 0)
			(type default)
		)
	)
	(wire
		(pts
			(xy 194.31 105.41) (xy 194.31 124.46)
		)
		(stroke
			(width 0)
			(type default)
		)
	)
	(bus
		(pts
			(xy 171.45 106.68) (xy 205.74 106.68)
		)
		(stroke
			(width 0)
			(type default)
		)
	)
	(wire
		(pts
			(xy 194.31 92.71) (xy 194.31 97.79)
		)
		(stroke
			(width 0)
			(type default)
		)
	)
	(wire
		(pts
			(xy 237.49 157.48) (xy 180.34 157.48)
		)
		(stroke
			(width 0)
			(type default)
		)
	)
	(wire
		(pts
			(xy 372.11 146.05) (xy 372.11 144.78)
		)
		(stroke
			(width 0)
			(type default)
		)
	)
	(wire
		(pts
			(xy 176.53 116.84) (xy 237.49 116.84)
		)
		(stroke
			(width 0)
			(type default)
		)
	)
	(wire
		(pts
			(xy 214.63 90.17) (xy 218.44 90.17)
		)
		(stroke
			(width 0)
			(type default)
		)
	)
	(wire
		(pts
			(xy 314.96 153.67) (xy 330.2 153.67)
		)
		(stroke
			(width 0)
			(type default)
		)
	)
	(wire
		(pts
			(xy 208.28 109.22) (xy 219.71 109.22)
		)
		(stroke
			(width 0)
			(type default)
		)
	)
	(bus
		(pts
			(xy 173.99 111.76) (xy 171.45 111.76)
		)
		(stroke
			(width 0)
			(type default)
		)
	)
	(wire
		(pts
			(xy 219.71 87.63) (xy 219.71 86.36)
		)
		(stroke
			(width 0)
			(type default)
		)
	)
	(wire
		(pts
			(xy 271.78 156.21) (xy 287.02 156.21)
		)
		(stroke
			(width 0)
			(type default)
		)
	)
	(bus
		(pts
			(xy 179.07 163.83) (xy 179.07 166.37)
		)
		(stroke
			(width 0)
			(type default)
		)
	)
	(wire
		(pts
			(xy 262.89 187.96) (xy 264.16 187.96)
		)
		(stroke
			(width 0)
			(type default)
		)
	)
	(wire
		(pts
			(xy 271.78 137.16) (xy 287.02 137.16)
		)
		(stroke
			(width 0)
			(type default)
		)
	)
	(wire
		(pts
			(xy 219.71 87.63) (xy 224.79 87.63)
		)
		(stroke
			(width 0)
			(type default)
		)
	)
	(wire
		(pts
			(xy 198.12 100.33) (xy 198.12 97.79)
		)
		(stroke
			(width 0)
			(type default)
		)
	)
	(bus
		(pts
			(xy 179.07 166.37) (xy 179.07 171.45)
		)
		(stroke
			(width 0)
			(type default)
		)
	)
	(wire
		(pts
			(xy 194.31 124.46) (xy 237.49 124.46)
		)
		(stroke
			(width 0)
			(type default)
		)
	)
	(wire
		(pts
			(xy 229.87 87.63) (xy 231.14 87.63)
		)
		(stroke
			(width 0)
			(type default)
		)
	)
	(wire
		(pts
			(xy 237.49 134.62) (xy 180.34 134.62)
		)
		(stroke
			(width 0)
			(type default)
		)
	)
	(wire
		(pts
			(xy 231.14 87.63) (xy 231.14 90.17)
		)
		(stroke
			(width 0)
			(type default)
		)
	)
	(wire
		(pts
			(xy 328.93 146.05) (xy 328.93 144.78)
		)
		(stroke
			(width 0)
			(type default)
		)
	)
	(wire
		(pts
			(xy 314.96 137.16) (xy 330.2 137.16)
		)
		(stroke
			(width 0)
			(type default)
		)
	)
	(wire
		(pts
			(xy 180.34 180.34) (xy 237.49 180.34)
		)
		(stroke
			(width 0)
			(type default)
		)
	)
	(wire
		(pts
			(xy 237.49 101.6) (xy 223.52 101.6)
		)
		(stroke
			(width 0)
			(type default)
		)
	)
	(bus
		(pts
			(xy 179.07 181.61) (xy 179.07 186.69)
		)
		(stroke
			(width 0)
			(type default)
		)
	)
	(bus
		(pts
			(xy 175.26 115.57) (xy 175.26 113.03)
		)
		(stroke
			(width 0)
			(type default)
		)
	)
	(wire
		(pts
			(xy 224.79 109.22) (xy 237.49 109.22)
		)
		(stroke
			(width 0)
			(type default)
		)
	)
	(wire
		(pts
			(xy 328.93 165.1) (xy 328.93 163.83)
		)
		(stroke
			(width 0)
			(type default)
		)
	)
	(wire
		(pts
			(xy 180.34 187.96) (xy 237.49 187.96)
		)
		(stroke
			(width 0)
			(type default)
		)
	)
	(wire
		(pts
			(xy 236.22 99.06) (xy 236.22 87.63)
		)
		(stroke
			(width 0)
			(type default)
		)
	)
	(wire
		(pts
			(xy 314.96 156.21) (xy 330.2 156.21)
		)
		(stroke
			(width 0)
			(type default)
		)
	)
	(wire
		(pts
			(xy 328.93 163.83) (xy 330.2 163.83)
		)
		(stroke
			(width 0)
			(type default)
		)
	)
	(wire
		(pts
			(xy 237.49 137.16) (xy 180.34 137.16)
		)
		(stroke
			(width 0)
			(type default)
		)
	)
	(wire
		(pts
			(xy 231.14 87.63) (xy 236.22 87.63)
		)
		(stroke
			(width 0)
			(type default)
		)
	)
	(wire
		(pts
			(xy 208.28 111.76) (xy 219.71 111.76)
		)
		(stroke
			(width 0)
			(type default)
		)
	)
	(bus
		(pts
			(xy 207.01 107.95) (xy 205.74 106.68)
		)
		(stroke
			(width 0)
			(type default)
		)
	)
	(wire
		(pts
			(xy 314.96 139.7) (xy 330.2 139.7)
		)
		(stroke
			(width 0)
			(type default)
		)
	)
	(label "I2C0.SDA"
		(at 208.28 111.76 0)
		(effects
			(font
				(size 1.27 1.27)
			)
			(justify left bottom)
		)
	)
	(label "PCIe_{x4}.TX2+"
		(at 181.61 180.34 0)
		(effects
			(font
				(size 1.27 1.27)
			)
			(justify left bottom)
		)
	)
	(label "PCIe_{REF0}.CK+"
		(at 358.14 134.62 0)
		(effects
			(font
				(size 1.27 1.27)
			)
			(justify left bottom)
		)
	)
	(label "PCIe_{x4}.RX2-"
		(at 181.61 152.4 0)
		(effects
			(font
				(size 1.27 1.27)
			)
			(justify left bottom)
		)
	)
	(label "PCIe_{x4}.RX1-"
		(at 181.61 144.78 0)
		(effects
			(font
				(size 1.27 1.27)
			)
			(justify left bottom)
		)
	)
	(label "~{CPRSNT_D0}"
		(at 223.52 127 0)
		(effects
			(font
				(size 1.27 1.27)
			)
			(justify left bottom)
		)
	)
	(label "PCIe_{x4}.RX1+"
		(at 181.61 142.24 0)
		(effects
			(font
				(size 1.27 1.27)
			)
			(justify left bottom)
		)
	)
	(label "PCIe_{x4}.TX3-"
		(at 181.61 190.5 0)
		(effects
			(font
				(size 1.27 1.27)
			)
			(justify left bottom)
		)
	)
	(label "PCIe_{x4}.RX0+"
		(at 181.61 134.62 0)
		(effects
			(font
				(size 1.27 1.27)
			)
			(justify left bottom)
		)
	)
	(label "PCIe_{x4}.TX0+"
		(at 314.96 134.62 0)
		(effects
			(font
				(size 1.27 1.27)
			)
			(justify left bottom)
		)
	)
	(label "PCIe_{x4}.TX2+"
		(at 314.96 153.67 0)
		(effects
			(font
				(size 1.27 1.27)
			)
			(justify left bottom)
		)
	)
	(label "PCIe_{x4}.TX1+"
		(at 314.96 139.7 0)
		(effects
			(font
				(size 1.27 1.27)
			)
			(justify left bottom)
		)
	)
	(label "PCIe_{x4}.TX3-"
		(at 314.96 161.29 0)
		(effects
			(font
				(size 1.27 1.27)
			)
			(justify left bottom)
		)
	)
	(label "SCL"
		(at 358.14 153.67 0)
		(effects
			(font
				(size 1.27 1.27)
			)
			(justify left bottom)
		)
	)
	(label "PCIe_{x4}.RX0-"
		(at 181.61 137.16 0)
		(effects
			(font
				(size 1.27 1.27)
			)
			(justify left bottom)
		)
	)
	(label "~{PERST_D0}"
		(at 223.52 124.46 0)
		(effects
			(font
				(size 1.27 1.27)
			)
			(justify left bottom)
		)
	)
	(label "PCIe_{x4}.RX2+"
		(at 271.78 153.67 0)
		(effects
			(font
				(size 1.27 1.27)
			)
			(justify left bottom)
		)
	)
	(label "PCIe_{x4}.RX0+"
		(at 271.78 134.62 0)
		(effects
			(font
				(size 1.27 1.27)
			)
			(justify left bottom)
		)
	)
	(label "V_{ACT_RX}0"
		(at 224.79 101.6 0)
		(effects
			(font
				(size 1.27 1.27)
			)
			(justify left bottom)
		)
	)
	(label "PCIe_{x4}.RX3+"
		(at 271.78 158.75 0)
		(effects
			(font
				(size 1.27 1.27)
			)
			(justify left bottom)
		)
	)
	(label "PCIe_{REF0}.CK-"
		(at 236.22 119.38 180)
		(effects
			(font
				(size 1.27 1.27)
			)
			(justify right bottom)
		)
	)
	(label "PCIe_{x4}.TX3+"
		(at 181.61 187.96 0)
		(effects
			(font
				(size 1.27 1.27)
			)
			(justify left bottom)
		)
	)
	(label "PCIe_{x4}.TX0-"
		(at 181.61 167.64 0)
		(effects
			(font
				(size 1.27 1.27)
			)
			(justify left bottom)
		)
	)
	(label "PCIe_{x4}.TX2-"
		(at 314.96 156.21 0)
		(effects
			(font
				(size 1.27 1.27)
			)
			(justify left bottom)
		)
	)
	(label "V_{ACT_TX}0"
		(at 224.79 104.14 0)
		(effects
			(font
				(size 1.27 1.27)
			)
			(justify left bottom)
		)
	)
	(label "SCL"
		(at 232.41 109.22 0)
		(effects
			(font
				(size 1.27 1.27)
			)
			(justify left bottom)
		)
	)
	(label "I2C0.SCL"
		(at 208.28 109.22 0)
		(effects
			(font
				(size 1.27 1.27)
			)
			(justify left bottom)
		)
	)
	(label "PCIe_{x4}.RX2-"
		(at 271.78 156.21 0)
		(effects
			(font
				(size 1.27 1.27)
			)
			(justify left bottom)
		)
	)
	(label "~{CPRSNT_D0}"
		(at 358.14 161.29 0)
		(effects
			(font
				(size 1.27 1.27)
			)
			(justify left bottom)
		)
	)
	(label "PCIe_{x4}.TX0-"
		(at 314.96 137.16 0)
		(effects
			(font
				(size 1.27 1.27)
			)
			(justify left bottom)
		)
	)
	(label "SDA"
		(at 358.14 156.21 0)
		(effects
			(font
				(size 1.27 1.27)
			)
			(justify left bottom)
		)
	)
	(label "PCIe_{REF0}.CK-"
		(at 358.14 137.16 0)
		(effects
			(font
				(size 1.27 1.27)
			)
			(justify left bottom)
		)
	)
	(label "PCIe_{x4}.RX3-"
		(at 181.61 160.02 0)
		(effects
			(font
				(size 1.27 1.27)
			)
			(justify left bottom)
		)
	)
	(label "PCIe_{x4}.RX2+"
		(at 181.61 149.86 0)
		(effects
			(font
				(size 1.27 1.27)
			)
			(justify left bottom)
		)
	)
	(label "PCIe_{x4}.RX1-"
		(at 271.78 142.24 0)
		(effects
			(font
				(size 1.27 1.27)
			)
			(justify left bottom)
		)
	)
	(label "PCIe_{x4}.TX1+"
		(at 181.61 172.72 0)
		(effects
			(font
				(size 1.27 1.27)
			)
			(justify left bottom)
		)
	)
	(label "PCIe_{x4}.RX1+"
		(at 271.78 139.7 0)
		(effects
			(font
				(size 1.27 1.27)
			)
			(justify left bottom)
		)
	)
	(label "PCIe_{REF0}.CK+"
		(at 236.22 116.84 180)
		(effects
			(font
				(size 1.27 1.27)
			)
			(justify right bottom)
		)
	)
	(label "5V_CONN0"
		(at 231.14 87.63 0)
		(effects
			(font
				(size 1.27 1.27)
			)
			(justify left bottom)
		)
	)
	(label "PCIe_{x4}.TX1-"
		(at 181.61 175.26 0)
		(effects
			(font
				(size 1.27 1.27)
			)
			(justify left bottom)
		)
	)
	(label "PCIe_{x4}.TX1-"
		(at 314.96 142.24 0)
		(effects
			(font
				(size 1.27 1.27)
			)
			(justify left bottom)
		)
	)
	(label "PCIe_{x4}.RX0-"
		(at 271.78 137.16 0)
		(effects
			(font
				(size 1.27 1.27)
			)
			(justify left bottom)
		)
	)
	(label "PCIe_{x4}.RX3-"
		(at 271.78 161.29 0)
		(effects
			(font
				(size 1.27 1.27)
			)
			(justify left bottom)
		)
	)
	(label "PCIe_{x4}.TX0+"
		(at 181.61 165.1 0)
		(effects
			(font
				(size 1.27 1.27)
			)
			(justify left bottom)
		)
	)
	(label "PCIe_{x4}.TX2-"
		(at 181.61 182.88 0)
		(effects
			(font
				(size 1.27 1.27)
			)
			(justify left bottom)
		)
	)
	(label "PCIe_{x4}.TX3+"
		(at 314.96 158.75 0)
		(effects
			(font
				(size 1.27 1.27)
			)
			(justify left bottom)
		)
	)
	(label "SDA"
		(at 232.41 111.76 0)
		(effects
			(font
				(size 1.27 1.27)
			)
			(justify left bottom)
		)
	)
	(label "~{PERST_D0}"
		(at 358.14 158.75 0)
		(effects
			(font
				(size 1.27 1.27)
			)
			(justify left bottom)
		)
	)
	(label "PCIe_{x4}.RX3+"
		(at 181.61 157.48 0)
		(effects
			(font
				(size 1.27 1.27)
			)
			(justify left bottom)
		)
	)
	(hierarchical_label "I2C0{I2C}"
		(shape input)
		(at 171.45 106.68 180)
		(effects
			(font
				(size 1.27 1.27)
			)
			(justify right)
		)
	)
	(hierarchical_label "PCIe_{REF0}{PCIe_{REF}}"
		(shape input)
		(at 171.45 111.76 180)
		(effects
			(font
				(size 1.27 1.27)
			)
			(justify right)
		)
	)
	(hierarchical_label "PCIe_{x4}{PCIe}"
		(shape input)
		(at 171.45 129.54 180)
		(effects
			(font
				(size 1.27 1.27)
			)
			(justify right)
		)
	)
	(hierarchical_label "~{CPRSNT0}"
		(shape output)
		(at 171.45 127 180)
		(effects
			(font
				(size 1.27 1.27)
			)
			(justify right)
		)
	)
	(hierarchical_label "~{PERST}"
		(shape input)
		(at 171.45 124.46 180)
		(effects
			(font
				(size 1.27 1.27)
			)
			(justify right)
		)
	)
	(symbol
		(lib_id "antmicroCapacitors0603:C_22u_16V_0603")
		(at 231.14 95.25 90)
		(unit 1)
		(exclude_from_sim no)
		(in_bom yes)
		(on_board yes)
		(dnp no)
		(property "Reference" "C38"
			(at 234.95 90.17 90)
			(effects
				(font
					(size 1.27 1.27)
					(thickness 0.15)
				)
				(justify left)
			)
		)
		(property "Value" "C_22u_16V_0603"
			(at 241.3 74.93 0)
			(effects
				(font
					(size 1.27 1.27)
					(thickness 0.15)
				)
				(justify left bottom)
				(hide yes)
			)
		)
		(property "Footprint" "antmicro-footprints:C_0603_1608Metric"
			(at 243.84 74.93 0)
			(effects
				(font
					(size 1.27 1.27)
					(thickness 0.15)
				)
				(justify left bottom)
				(hide yes)
			)
		)
		(property "Datasheet" "https://product.samsungsem.com/mlcc/CL10A226MO7JZN.do"
			(at 246.38 74.93 0)
			(effects
				(font
					(size 1.27 1.27)
					(thickness 0.15)
				)
				(justify left bottom)
				(hide yes)
			)
		)
		(property "Description" ""
			(at 231.14 95.25 0)
			(effects
				(font
					(size 1.27 1.27)
				)
				(hide yes)
			)
		)
		(property "MPN" "CL10A226MO7JZNC"
			(at 248.92 74.93 0)
			(effects
				(font
					(size 1.27 1.27)
					(thickness 0.15)
				)
				(justify left bottom)
				(hide yes)
			)
		)
		(property "Manufacturer" "Samsung Electro-Mechanics"
			(at 251.46 74.93 0)
			(effects
				(font
					(size 1.27 1.27)
					(thickness 0.15)
				)
				(justify left bottom)
				(hide yes)
			)
		)
		(property "License" "Apache-2.0"
			(at 254 74.93 0)
			(effects
				(font
					(size 1.27 1.27)
					(thickness 0.15)
				)
				(justify left bottom)
				(hide yes)
			)
		)
		(property "Author" "Antmicro"
			(at 256.54 74.93 0)
			(effects
				(font
					(size 1.27 1.27)
					(thickness 0.15)
				)
				(justify left bottom)
				(hide yes)
			)
		)
		(property "Val" "22u"
			(at 234.95 93.98 90)
			(effects
				(font
					(size 1.27 1.27)
					(thickness 0.15)
				)
				(justify left bottom)
			)
		)
		(property "Voltage" "16V"
			(at 259.08 74.93 0)
			(effects
				(font
					(size 1.27 1.27)
				)
				(justify left bottom)
				(hide yes)
			)
		)
		(property "Dielectric" ""
			(at 261.62 74.93 0)
			(effects
				(font
					(size 1.27 1.27)
				)
				(justify left bottom)
				(hide yes)
			)
		)
		(property "Public" "False"
			(at 264.16 74.93 0)
			(effects
				(font
					(size 1.27 1.27)
				)
				(justify left bottom)
				(hide yes)
			)
		)
		(pin "1"
		)
		(pin "2"
		)
		(instances
			(project "com-express-7-baseboard"
				(path ""
					(reference "C38")
					(unit 1)
				)
			)
		)
	)
	(symbol
		(lib_id "antmicroResistorsmisc:R_0R001_0805")
		(at 224.79 87.63 0)
		(unit 1)
		(exclude_from_sim no)
		(in_bom yes)
		(on_board yes)
		(dnp no)
		(property "Reference" "R82"
			(at 227.33 82.55 0)
			(effects
				(font
					(size 1.27 1.27)
					(thickness 0.15)
				)
			)
		)
		(property "Value" "R_0R001_0805"
			(at 245.11 100.33 0)
			(effects
				(font
					(size 1.27 1.27)
					(thickness 0.15)
				)
				(justify left bottom)
				(hide yes)
			)
		)
		(property "Footprint" "antmicro-footprints:R_0805_2012Metric"
			(at 245.11 102.87 0)
			(effects
				(font
					(size 1.27 1.27)
					(thickness 0.15)
				)
				(justify left bottom)
				(hide yes)
			)
		)
		(property "Datasheet" "https://www.eaton.com/content/dam/eaton/products/electronic-components/resources/data-sheet/eaton-msma-automotive-smd-current-sense-resistor-metal-strip-data-sheet-elx1179.pdf"
			(at 245.11 105.41 0)
			(effects
				(font
					(size 1.27 1.27)
					(thickness 0.15)
				)
				(justify left bottom)
				(hide yes)
			)
		)
		(property "Description" ""
			(at 224.79 87.63 0)
			(effects
				(font
					(size 1.27 1.27)
				)
				(hide yes)
			)
		)
		(property "MPN" "MSMA0805R0010FSM"
			(at 245.11 107.95 0)
			(effects
				(font
					(size 1.27 1.27)
					(thickness 0.15)
				)
				(justify left bottom)
				(hide yes)
			)
		)
		(property "Manufacturer" "Eaton"
			(at 245.11 110.49 0)
			(effects
				(font
					(size 1.27 1.27)
					(thickness 0.15)
				)
				(justify left bottom)
				(hide yes)
			)
		)
		(property "License" "Apache-2.0"
			(at 245.11 113.03 0)
			(effects
				(font
					(size 1.27 1.27)
					(thickness 0.15)
				)
				(justify left bottom)
				(hide yes)
			)
		)
		(property "Author" "Antmicro"
			(at 245.11 115.57 0)
			(effects
				(font
					(size 1.27 1.27)
					(thickness 0.15)
				)
				(justify left bottom)
				(hide yes)
			)
		)
		(property "Val" "0R001"
			(at 227.33 85.09 0)
			(effects
				(font
					(size 1.27 1.27)
					(thickness 0.15)
				)
			)
		)
		(property "Tolerance" "1%"
			(at 245.11 97.79 0)
			(effects
				(font
					(size 1.27 1.27)
				)
				(justify left bottom)
				(hide yes)
			)
		)
		(property "Public" "False"
			(at 245.11 118.11 0)
			(effects
				(font
					(size 1.27 1.27)
				)
				(justify left bottom)
				(hide yes)
			)
		)
		(pin "2"
		)
		(pin "1"
		)
		(instances
			(project "com-express-7-baseboard"
				(path ""
					(reference "R82")
					(unit 1)
				)
			)
		)
	)
	(symbol
		(lib_id "antmicroPciConnectors:OCuLink_x4_Amphenol_G14A421211112HR")
		(at 237.49 99.06 0)
		(unit 1)
		(exclude_from_sim no)
		(in_bom yes)
		(on_board yes)
		(dnp no)
		(fields_autoplaced yes)
		(property "Reference" "J4"
			(at 250.19 91.44 0)
			(effects
				(font
					(size 1.27 1.27)
					(thickness 0.15)
				)
			)
		)
		(property "Value" "OCuLink_x4_Amphenol_G14A421211112HR"
			(at 276.86 111.76 0)
			(effects
				(font
					(size 1.27 1.27)
					(thickness 0.15)
				)
				(justify left bottom)
				(hide yes)
			)
		)
		(property "Footprint" "antmicro-footprints:Amphenol_G14A421211112HR"
			(at 276.86 114.3 0)
			(effects
				(font
					(size 1.27 1.27)
					(thickness 0.15)
				)
				(justify left bottom)
				(hide yes)
			)
		)
		(property "Datasheet" "https://cdn.amphenol-cs.com/media/wysiwyg/files/drawing/g14a421x1bxxxhr.pdf"
			(at 276.86 116.84 0)
			(effects
				(font
					(size 1.27 1.27)
					(thickness 0.15)
				)
				(justify left bottom)
				(hide yes)
			)
		)
		(property "Description" ""
			(at 237.49 99.06 0)
			(effects
				(font
					(size 1.27 1.27)
				)
				(hide yes)
			)
		)
		(property "Manufacturer" "Amphenol"
			(at 276.86 106.68 0)
			(effects
				(font
					(size 1.27 1.27)
					(thickness 0.15)
				)
				(justify left bottom)
				(hide yes)
			)
		)
		(property "MPN" "G14A421211112HR"
			(at 250.19 93.98 0)
			(effects
				(font
					(size 1.27 1.27)
					(thickness 0.15)
				)
			)
		)
		(property "Author" "Antmicro"
			(at 276.86 119.38 0)
			(effects
				(font
					(size 1.27 1.27)
					(thickness 0.15)
				)
				(justify left bottom)
				(hide yes)
			)
		)
		(property "License" "Apache-2.0"
			(at 276.86 121.92 0)
			(effects
				(font
					(size 1.27 1.27)
					(thickness 0.15)
				)
				(justify left bottom)
				(hide yes)
			)
		)
		(pin "B1"
		)
		(pin "A19"
		)
		(pin "B8"
		)
		(pin "B20"
		)
		(pin "A4"
		)
		(pin "B16"
		)
		(pin "A1"
		)
		(pin "A16"
		)
		(pin "B21"
		)
		(pin "B4"
		)
		(pin "B3"
		)
		(pin "B7"
		)
		(pin "B5"
		)
		(pin "B13"
		)
		(pin "SH"
		)
		(pin "A11"
		)
		(pin "A13"
		)
		(pin "B15"
		)
		(pin "B9"
		)
		(pin "A8"
		)
		(pin "B18"
		)
		(pin "A3"
		)
		(pin "B17"
		)
		(pin "A9"
		)
		(pin "A21"
		)
		(pin "B11"
		)
		(pin "B10"
		)
		(pin "A12"
		)
		(pin "B6"
		)
		(pin "A10"
		)
		(pin "B12"
		)
		(pin "A6"
		)
		(pin "B14"
		)
		(pin "A18"
		)
		(pin "B19"
		)
		(pin "A5"
		)
		(pin "A17"
		)
		(pin "A20"
		)
		(pin "A7"
		)
		(pin "A2"
		)
		(pin "A14"
		)
		(pin "A15"
		)
		(pin "B2"
		)
		(instances
			(project "com-express-7-baseboard"
				(path ""
					(reference "J4")
					(unit 1)
				)
			)
		)
	)
	(symbol
		(lib_id "antmicroResistors0402:R_0R_0402")
		(at 209.55 92.71 180)
		(unit 1)
		(exclude_from_sim no)
		(in_bom yes)
		(on_board yes)
		(dnp no)
		(property "Reference" "R81"
			(at 203.2 91.44 0)
			(effects
				(font
					(size 1.27 1.27)
					(thickness 0.15)
				)
			)
		)
		(property "Value" "R_0R_0402"
			(at 189.23 80.01 0)
			(effects
				(font
					(size 1.27 1.27)
					(thickness 0.15)
				)
				(justify left bottom)
				(hide yes)
			)
		)
		(property "Footprint" "antmicro-footprints:R_0402_1005Metric"
			(at 189.23 77.47 0)
			(effects
				(font
					(size 1.27 1.27)
					(thickness 0.15)
				)
				(justify left bottom)
				(hide yes)
			)
		)
		(property "Datasheet" "https://industrial.panasonic.com/cdbs/www-data/pdf/RDA0000/AOA0000C301.pdf"
			(at 189.23 74.93 0)
			(effects
				(font
					(size 1.27 1.27)
					(thickness 0.15)
				)
				(justify left bottom)
				(hide yes)
			)
		)
		(property "Description" ""
			(at 209.55 92.71 0)
			(effects
				(font
					(size 1.27 1.27)
				)
				(hide yes)
			)
		)
		(property "MPN" "ERJ2GE0R00X"
			(at 189.23 72.39 0)
			(effects
				(font
					(size 1.27 1.27)
					(thickness 0.15)
				)
				(justify left bottom)
				(hide yes)
			)
		)
		(property "Manufacturer" "Panasonic"
			(at 189.23 69.85 0)
			(effects
				(font
					(size 1.27 1.27)
					(thickness 0.15)
				)
				(justify left bottom)
				(hide yes)
			)
		)
		(property "License" "Apache-2.0"
			(at 189.23 67.31 0)
			(effects
				(font
					(size 1.27 1.27)
					(thickness 0.15)
				)
				(justify left bottom)
				(hide yes)
			)
		)
		(property "Author" "Antmicro"
			(at 189.23 64.77 0)
			(effects
				(font
					(size 1.27 1.27)
					(thickness 0.15)
				)
				(justify left bottom)
				(hide yes)
			)
		)
		(property "Val" "0R"
			(at 210.82 91.44 0)
			(effects
				(font
					(size 1.27 1.27)
					(thickness 0.15)
				)
			)
		)
		(property "Tolerance" "~"
			(at 189.23 82.55 0)
			(effects
				(font
					(size 1.27 1.27)
				)
				(justify left bottom)
				(hide yes)
			)
		)
		(property "Current" "1A"
			(at 189.23 62.23 0)
			(effects
				(font
					(size 1.27 1.27)
					(thickness 0.15)
				)
				(justify left bottom)
				(hide yes)
			)
		)
		(property "Public" "False"
			(at 189.23 62.23 0)
			(effects
				(font
					(size 1.27 1.27)
				)
				(justify left bottom)
				(hide yes)
			)
		)
		(pin "2"
		)
		(pin "1"
		)
		(instances
			(project "com-express-7-baseboard"
				(path ""
					(reference "R81")
					(unit 1)
				)
			)
		)
	)
	(symbol
		(lib_id "antmicropower:GND")
		(at 285.75 165.1 0)
		(unit 1)
		(exclude_from_sim no)
		(in_bom yes)
		(on_board yes)
		(dnp no)
		(property "Reference" "#PWR077"
			(at 294.64 167.64 0)
			(effects
				(font
					(size 1.27 1.27)
					(thickness 0.15)
				)
				(justify left bottom)
				(hide yes)
			)
		)
		(property "Value" "GND"
			(at 285.75 168.91 0)
			(effects
				(font
					(size 1.27 1.27)
					(thickness 0.15)
				)
			)
		)
		(property "Footprint" ""
			(at 294.64 172.72 0)
			(effects
				(font
					(size 1.27 1.27)
					(thickness 0.15)
				)
				(justify left bottom)
				(hide yes)
			)
		)
		(property "Datasheet" ""
			(at 294.64 177.8 0)
			(effects
				(font
					(size 1.27 1.27)
					(thickness 0.15)
				)
				(justify left bottom)
				(hide yes)
			)
		)
		(property "Description" ""
			(at 285.75 165.1 0)
			(effects
				(font
					(size 1.27 1.27)
				)
				(hide yes)
			)
		)
		(property "Author" "Antmicro"
			(at 294.64 172.72 0)
			(effects
				(font
					(size 1.27 1.27)
					(thickness 0.15)
				)
				(justify left bottom)
				(hide yes)
			)
		)
		(property "License" "Apache-2.0"
			(at 294.64 175.26 0)
			(effects
				(font
					(size 1.27 1.27)
					(thickness 0.15)
				)
				(justify left bottom)
				(hide yes)
			)
		)
		(pin "1"
		)
		(instances
			(project "com-express-7-baseboard"
				(path ""
					(reference "#PWR077")
					(unit 1)
				)
			)
		)
	)
	(symbol
		(lib_id "antmicropower:GND")
		(at 328.93 165.1 0)
		(unit 1)
		(exclude_from_sim no)
		(in_bom yes)
		(on_board yes)
		(dnp no)
		(property "Reference" "#PWR079"
			(at 337.82 167.64 0)
			(effects
				(font
					(size 1.27 1.27)
					(thickness 0.15)
				)
				(justify left bottom)
				(hide yes)
			)
		)
		(property "Value" "GND"
			(at 328.93 168.91 0)
			(effects
				(font
					(size 1.27 1.27)
					(thickness 0.15)
				)
			)
		)
		(property "Footprint" ""
			(at 337.82 172.72 0)
			(effects
				(font
					(size 1.27 1.27)
					(thickness 0.15)
				)
				(justify left bottom)
				(hide yes)
			)
		)
		(property "Datasheet" ""
			(at 337.82 177.8 0)
			(effects
				(font
					(size 1.27 1.27)
					(thickness 0.15)
				)
				(justify left bottom)
				(hide yes)
			)
		)
		(property "Description" ""
			(at 328.93 165.1 0)
			(effects
				(font
					(size 1.27 1.27)
				)
				(hide yes)
			)
		)
		(property "Author" "Antmicro"
			(at 337.82 172.72 0)
			(effects
				(font
					(size 1.27 1.27)
					(thickness 0.15)
				)
				(justify left bottom)
				(hide yes)
			)
		)
		(property "License" "Apache-2.0"
			(at 337.82 175.26 0)
			(effects
				(font
					(size 1.27 1.27)
					(thickness 0.15)
				)
				(justify left bottom)
				(hide yes)
			)
		)
		(pin "1"
		)
		(instances
			(project "com-express-7-baseboard"
				(path ""
					(reference "#PWR079")
					(unit 1)
				)
			)
		)
	)
	(symbol
		(lib_id "antmicropower:GND")
		(at 210.82 99.06 0)
		(unit 1)
		(exclude_from_sim no)
		(in_bom yes)
		(on_board yes)
		(dnp no)
		(property "Reference" "#PWR071"
			(at 219.71 101.6 0)
			(effects
				(font
					(size 1.27 1.27)
					(thickness 0.15)
				)
				(justify left bottom)
				(hide yes)
			)
		)
		(property "Value" "GND"
			(at 210.82 102.87 0)
			(effects
				(font
					(size 1.27 1.27)
					(thickness 0.15)
				)
			)
		)
		(property "Footprint" ""
			(at 219.71 106.68 0)
			(effects
				(font
					(size 1.27 1.27)
					(thickness 0.15)
				)
				(justify left bottom)
				(hide yes)
			)
		)
		(property "Datasheet" ""
			(at 219.71 111.76 0)
			(effects
				(font
					(size 1.27 1.27)
					(thickness 0.15)
				)
				(justify left bottom)
				(hide yes)
			)
		)
		(property "Description" ""
			(at 210.82 99.06 0)
			(effects
				(font
					(size 1.27 1.27)
				)
				(hide yes)
			)
		)
		(property "Author" "Antmicro"
			(at 219.71 106.68 0)
			(effects
				(font
					(size 1.27 1.27)
					(thickness 0.15)
				)
				(justify left bottom)
				(hide yes)
			)
		)
		(property "License" "Apache-2.0"
			(at 219.71 109.22 0)
			(effects
				(font
					(size 1.27 1.27)
					(thickness 0.15)
				)
				(justify left bottom)
				(hide yes)
			)
		)
		(pin "1"
		)
		(instances
			(project "com-express-7-baseboard"
				(path ""
					(reference "#PWR071")
					(unit 1)
				)
			)
		)
	)
	(symbol
		(lib_id "antmicroResistors0402:R_0R_0402")
		(at 185.42 124.46 0)
		(unit 1)
		(exclude_from_sim no)
		(in_bom yes)
		(on_board yes)
		(dnp no)
		(property "Reference" "R76"
			(at 185.42 123.19 0)
			(effects
				(font
					(size 1.27 1.27)
					(thickness 0.15)
				)
				(justify right)
			)
		)
		(property "Value" "R_0R_0402"
			(at 205.74 137.16 0)
			(effects
				(font
					(size 1.27 1.27)
					(thickness 0.15)
				)
				(justify left bottom)
				(hide yes)
			)
		)
		(property "Footprint" "antmicro-footprints:R_0402_1005Metric"
			(at 205.74 139.7 0)
			(effects
				(font
					(size 1.27 1.27)
					(thickness 0.15)
				)
				(justify left bottom)
				(hide yes)
			)
		)
		(property "Datasheet" "https://industrial.panasonic.com/cdbs/www-data/pdf/RDA0000/AOA0000C301.pdf"
			(at 205.74 142.24 0)
			(effects
				(font
					(size 1.27 1.27)
					(thickness 0.15)
				)
				(justify left bottom)
				(hide yes)
			)
		)
		(property "Description" ""
			(at 185.42 124.46 0)
			(effects
				(font
					(size 1.27 1.27)
				)
				(hide yes)
			)
		)
		(property "MPN" "ERJ2GE0R00X"
			(at 205.74 144.78 0)
			(effects
				(font
					(size 1.27 1.27)
					(thickness 0.15)
				)
				(justify left bottom)
				(hide yes)
			)
		)
		(property "Manufacturer" "Panasonic"
			(at 205.74 147.32 0)
			(effects
				(font
					(size 1.27 1.27)
					(thickness 0.15)
				)
				(justify left bottom)
				(hide yes)
			)
		)
		(property "License" "Apache-2.0"
			(at 205.74 149.86 0)
			(effects
				(font
					(size 1.27 1.27)
					(thickness 0.15)
				)
				(justify left bottom)
				(hide yes)
			)
		)
		(property "Author" "Antmicro"
			(at 205.74 152.4 0)
			(effects
				(font
					(size 1.27 1.27)
					(thickness 0.15)
				)
				(justify left bottom)
				(hide yes)
			)
		)
		(property "Val" "0R"
			(at 191.77 123.19 0)
			(effects
				(font
					(size 1.27 1.27)
					(thickness 0.15)
				)
			)
		)
		(property "Tolerance" "~"
			(at 205.74 134.62 0)
			(effects
				(font
					(size 1.27 1.27)
				)
				(justify left bottom)
				(hide yes)
			)
		)
		(property "Current" "1A"
			(at 205.74 154.94 0)
			(effects
				(font
					(size 1.27 1.27)
					(thickness 0.15)
				)
				(justify left bottom)
				(hide yes)
			)
		)
		(property "Public" "False"
			(at 205.74 154.94 0)
			(effects
				(font
					(size 1.27 1.27)
				)
				(justify left bottom)
				(hide yes)
			)
		)
		(pin "1"
		)
		(pin "2"
		)
		(instances
			(project "com-express-7-baseboard"
				(path ""
					(reference "R76")
					(unit 1)
				)
			)
		)
	)
	(symbol
		(lib_id "antmicroCapacitors0603:C_22u_16V_0603")
		(at 210.82 99.06 90)
		(unit 1)
		(exclude_from_sim no)
		(in_bom yes)
		(on_board yes)
		(dnp no)
		(property "Reference" "C36"
			(at 211.455 94.615 90)
			(effects
				(font
					(size 1.27 1.27)
					(thickness 0.15)
				)
				(justify right)
			)
		)
		(property "Value" "C_22u_16V_0603"
			(at 220.98 78.74 0)
			(effects
				(font
					(size 1.27 1.27)
					(thickness 0.15)
				)
				(justify left bottom)
				(hide yes)
			)
		)
		(property "Footprint" "antmicro-footprints:C_0603_1608Metric"
			(at 223.52 78.74 0)
			(effects
				(font
					(size 1.27 1.27)
					(thickness 0.15)
				)
				(justify left bottom)
				(hide yes)
			)
		)
		(property "Datasheet" "https://product.samsungsem.com/mlcc/CL10A226MO7JZN.do"
			(at 226.06 78.74 0)
			(effects
				(font
					(size 1.27 1.27)
					(thickness 0.15)
				)
				(justify left bottom)
				(hide yes)
			)
		)
		(property "Description" ""
			(at 210.82 99.06 0)
			(effects
				(font
					(size 1.27 1.27)
				)
				(hide yes)
			)
		)
		(property "MPN" "CL10A226MO7JZNC"
			(at 228.6 78.74 0)
			(effects
				(font
					(size 1.27 1.27)
					(thickness 0.15)
				)
				(justify left bottom)
				(hide yes)
			)
		)
		(property "Manufacturer" "Samsung Electro-Mechanics"
			(at 231.14 78.74 0)
			(effects
				(font
					(size 1.27 1.27)
					(thickness 0.15)
				)
				(justify left bottom)
				(hide yes)
			)
		)
		(property "License" "Apache-2.0"
			(at 233.68 78.74 0)
			(effects
				(font
					(size 1.27 1.27)
					(thickness 0.15)
				)
				(justify left bottom)
				(hide yes)
			)
		)
		(property "Author" "Antmicro"
			(at 236.22 78.74 0)
			(effects
				(font
					(size 1.27 1.27)
					(thickness 0.15)
				)
				(justify left bottom)
				(hide yes)
			)
		)
		(property "Val" "22u"
			(at 214.63 97.79 90)
			(effects
				(font
					(size 1.27 1.27)
					(thickness 0.15)
				)
				(justify left bottom)
			)
		)
		(property "Voltage" "16V"
			(at 238.76 78.74 0)
			(effects
				(font
					(size 1.27 1.27)
				)
				(justify left bottom)
				(hide yes)
			)
		)
		(property "Dielectric" ""
			(at 241.3 78.74 0)
			(effects
				(font
					(size 1.27 1.27)
				)
				(justify left bottom)
				(hide yes)
			)
		)
		(property "Public" "False"
			(at 243.84 78.74 0)
			(effects
				(font
					(size 1.27 1.27)
				)
				(justify left bottom)
				(hide yes)
			)
		)
		(pin "1"
		)
		(pin "2"
		)
		(instances
			(project "com-express-7-baseboard"
				(path ""
					(reference "C36")
					(unit 1)
				)
			)
		)
	)
	(symbol
		(lib_id "antmicropower:GND")
		(at 264.16 191.77 0)
		(unit 1)
		(exclude_from_sim no)
		(in_bom yes)
		(on_board yes)
		(dnp no)
		(property "Reference" "#PWR075"
			(at 273.05 194.31 0)
			(effects
				(font
					(size 1.27 1.27)
					(thickness 0.15)
				)
				(justify left bottom)
				(hide yes)
			)
		)
		(property "Value" "GND"
			(at 264.16 195.58 0)
			(effects
				(font
					(size 1.27 1.27)
					(thickness 0.15)
				)
			)
		)
		(property "Footprint" ""
			(at 273.05 199.39 0)
			(effects
				(font
					(size 1.27 1.27)
					(thickness 0.15)
				)
				(justify left bottom)
				(hide yes)
			)
		)
		(property "Datasheet" ""
			(at 273.05 204.47 0)
			(effects
				(font
					(size 1.27 1.27)
					(thickness 0.15)
				)
				(justify left bottom)
				(hide yes)
			)
		)
		(property "Description" ""
			(at 264.16 191.77 0)
			(effects
				(font
					(size 1.27 1.27)
				)
				(hide yes)
			)
		)
		(property "Author" "Antmicro"
			(at 273.05 199.39 0)
			(effects
				(font
					(size 1.27 1.27)
					(thickness 0.15)
				)
				(justify left bottom)
				(hide yes)
			)
		)
		(property "License" "Apache-2.0"
			(at 273.05 201.93 0)
			(effects
				(font
					(size 1.27 1.27)
					(thickness 0.15)
				)
				(justify left bottom)
				(hide yes)
			)
		)
		(pin "1"
		)
		(instances
			(project "com-express-7-baseboard"
				(path ""
					(reference "#PWR075")
					(unit 1)
				)
			)
		)
	)
	(symbol
		(lib_id "antmicroResistors0402:R_0R_0402")
		(at 209.55 90.17 180)
		(unit 1)
		(exclude_from_sim no)
		(in_bom yes)
		(on_board yes)
		(dnp no)
		(property "Reference" "R80"
			(at 201.295 88.9 0)
			(effects
				(font
					(size 1.27 1.27)
					(thickness 0.15)
				)
				(justify right)
			)
		)
		(property "Value" "R_0R_0402"
			(at 189.23 77.47 0)
			(effects
				(font
					(size 1.27 1.27)
					(thickness 0.15)
				)
				(justify left bottom)
				(hide yes)
			)
		)
		(property "Footprint" "antmicro-footprints:R_0402_1005Metric"
			(at 189.23 74.93 0)
			(effects
				(font
					(size 1.27 1.27)
					(thickness 0.15)
				)
				(justify left bottom)
				(hide yes)
			)
		)
		(property "Datasheet" "https://industrial.panasonic.com/cdbs/www-data/pdf/RDA0000/AOA0000C301.pdf"
			(at 189.23 72.39 0)
			(effects
				(font
					(size 1.27 1.27)
					(thickness 0.15)
				)
				(justify left bottom)
				(hide yes)
			)
		)
		(property "Description" ""
			(at 209.55 90.17 0)
			(effects
				(font
					(size 1.27 1.27)
				)
				(hide yes)
			)
		)
		(property "MPN" "ERJ2GE0R00X"
			(at 189.23 69.85 0)
			(effects
				(font
					(size 1.27 1.27)
					(thickness 0.15)
				)
				(justify left bottom)
				(hide yes)
			)
		)
		(property "Manufacturer" "Panasonic"
			(at 189.23 67.31 0)
			(effects
				(font
					(size 1.27 1.27)
					(thickness 0.15)
				)
				(justify left bottom)
				(hide yes)
			)
		)
		(property "License" "Apache-2.0"
			(at 189.23 64.77 0)
			(effects
				(font
					(size 1.27 1.27)
					(thickness 0.15)
				)
				(justify left bottom)
				(hide yes)
			)
		)
		(property "Author" "Antmicro"
			(at 189.23 62.23 0)
			(effects
				(font
					(size 1.27 1.27)
					(thickness 0.15)
				)
				(justify left bottom)
				(hide yes)
			)
		)
		(property "Val" "0R"
			(at 209.55 88.9 0)
			(effects
				(font
					(size 1.27 1.27)
					(thickness 0.15)
				)
				(justify right)
			)
		)
		(property "Tolerance" "~"
			(at 189.23 80.01 0)
			(effects
				(font
					(size 1.27 1.27)
				)
				(justify left bottom)
				(hide yes)
			)
		)
		(property "Current" "1A"
			(at 189.23 59.69 0)
			(effects
				(font
					(size 1.27 1.27)
					(thickness 0.15)
				)
				(justify left bottom)
				(hide yes)
			)
		)
		(property "Public" "False"
			(at 189.23 59.69 0)
			(effects
				(font
					(size 1.27 1.27)
				)
				(justify left bottom)
				(hide yes)
			)
		)
		(pin "2"
		)
		(pin "1"
		)
		(instances
			(project "com-express-7-baseboard"
				(path ""
					(reference "R80")
					(unit 1)
				)
			)
		)
	)
	(symbol
		(lib_id "antmicropower:GND")
		(at 231.14 95.25 0)
		(unit 1)
		(exclude_from_sim no)
		(in_bom yes)
		(on_board yes)
		(dnp no)
		(property "Reference" "#PWR074"
			(at 240.03 97.79 0)
			(effects
				(font
					(size 1.27 1.27)
					(thickness 0.15)
				)
				(justify left bottom)
				(hide yes)
			)
		)
		(property "Value" "GND"
			(at 231.14 99.06 0)
			(effects
				(font
					(size 1.27 1.27)
					(thickness 0.15)
				)
			)
		)
		(property "Footprint" ""
			(at 240.03 102.87 0)
			(effects
				(font
					(size 1.27 1.27)
					(thickness 0.15)
				)
				(justify left bottom)
				(hide yes)
			)
		)
		(property "Datasheet" ""
			(at 240.03 107.95 0)
			(effects
				(font
					(size 1.27 1.27)
					(thickness 0.15)
				)
				(justify left bottom)
				(hide yes)
			)
		)
		(property "Description" ""
			(at 231.14 95.25 0)
			(effects
				(font
					(size 1.27 1.27)
				)
				(hide yes)
			)
		)
		(property "Author" "Antmicro"
			(at 240.03 102.87 0)
			(effects
				(font
					(size 1.27 1.27)
					(thickness 0.15)
				)
				(justify left bottom)
				(hide yes)
			)
		)
		(property "License" "Apache-2.0"
			(at 240.03 105.41 0)
			(effects
				(font
					(size 1.27 1.27)
					(thickness 0.15)
				)
				(justify left bottom)
				(hide yes)
			)
		)
		(pin "1"
		)
		(instances
			(project "com-express-7-baseboard"
				(path ""
					(reference "#PWR074")
					(unit 1)
				)
			)
		)
	)
	(symbol
		(lib_id "antmicropower:GND")
		(at 218.44 99.06 0)
		(unit 1)
		(exclude_from_sim no)
		(in_bom yes)
		(on_board yes)
		(dnp no)
		(property "Reference" "#PWR072"
			(at 227.33 101.6 0)
			(effects
				(font
					(size 1.27 1.27)
					(thickness 0.15)
				)
				(justify left bottom)
				(hide yes)
			)
		)
		(property "Value" "GND"
			(at 218.44 102.87 0)
			(effects
				(font
					(size 1.27 1.27)
					(thickness 0.15)
				)
			)
		)
		(property "Footprint" ""
			(at 227.33 106.68 0)
			(effects
				(font
					(size 1.27 1.27)
					(thickness 0.15)
				)
				(justify left bottom)
				(hide yes)
			)
		)
		(property "Datasheet" ""
			(at 227.33 111.76 0)
			(effects
				(font
					(size 1.27 1.27)
					(thickness 0.15)
				)
				(justify left bottom)
				(hide yes)
			)
		)
		(property "Description" ""
			(at 218.44 99.06 0)
			(effects
				(font
					(size 1.27 1.27)
				)
				(hide yes)
			)
		)
		(property "Author" "Antmicro"
			(at 227.33 106.68 0)
			(effects
				(font
					(size 1.27 1.27)
					(thickness 0.15)
				)
				(justify left bottom)
				(hide yes)
			)
		)
		(property "License" "Apache-2.0"
			(at 227.33 109.22 0)
			(effects
				(font
					(size 1.27 1.27)
					(thickness 0.15)
				)
				(justify left bottom)
				(hide yes)
			)
		)
		(pin "1"
		)
		(instances
			(project "com-express-7-baseboard"
				(path ""
					(reference "#PWR072")
					(unit 1)
				)
			)
		)
	)
	(symbol
		(lib_id "antmicropower:+3V3")
		(at 194.31 88.9 0)
		(unit 1)
		(exclude_from_sim no)
		(in_bom yes)
		(on_board yes)
		(dnp no)
		(property "Reference" "#PWR070"
			(at 209.55 88.9 0)
			(effects
				(font
					(size 1.27 1.27)
					(thickness 0.15)
				)
				(justify left bottom)
				(hide yes)
			)
		)
		(property "Value" "+3V3"
			(at 194.31 85.09 0)
			(effects
				(font
					(size 1.27 1.27)
					(thickness 0.15)
				)
			)
		)
		(property "Footprint" ""
			(at 209.55 96.52 0)
			(effects
				(font
					(size 1.27 1.27)
					(thickness 0.15)
				)
				(justify left bottom)
				(hide yes)
			)
		)
		(property "Datasheet" ""
			(at 209.55 99.06 0)
			(effects
				(font
					(size 1.27 1.27)
					(thickness 0.15)
				)
				(justify left bottom)
				(hide yes)
			)
		)
		(property "Description" ""
			(at 194.31 88.9 0)
			(effects
				(font
					(size 1.27 1.27)
				)
				(hide yes)
			)
		)
		(property "Author" "Antmicro"
			(at 209.55 91.44 0)
			(effects
				(font
					(size 1.27 1.27)
					(thickness 0.15)
				)
				(justify left bottom)
				(hide yes)
			)
		)
		(property "License" "Apache-2.0"
			(at 209.55 93.98 0)
			(effects
				(font
					(size 1.27 1.27)
					(thickness 0.15)
				)
				(justify left bottom)
				(hide yes)
			)
		)
		(pin "1"
		)
		(instances
			(project "com-express-7-baseboard"
				(path ""
					(reference "#PWR070")
					(unit 1)
				)
			)
		)
	)
	(symbol
		(lib_id "antmicropower:+5V")
		(at 219.71 86.36 0)
		(unit 1)
		(exclude_from_sim no)
		(in_bom yes)
		(on_board yes)
		(dnp no)
		(property "Reference" "#PWR073"
			(at 234.95 88.9 0)
			(effects
				(font
					(size 1.27 1.27)
					(thickness 0.15)
				)
				(justify left bottom)
				(hide yes)
			)
		)
		(property "Value" "+5V"
			(at 219.71 82.55 0)
			(effects
				(font
					(size 1.27 1.27)
					(thickness 0.15)
				)
			)
		)
		(property "Footprint" ""
			(at 234.95 93.98 0)
			(effects
				(font
					(size 1.27 1.27)
					(thickness 0.15)
				)
				(justify left bottom)
				(hide yes)
			)
		)
		(property "Datasheet" ""
			(at 234.95 96.52 0)
			(effects
				(font
					(size 1.27 1.27)
					(thickness 0.15)
				)
				(justify left bottom)
				(hide yes)
			)
		)
		(property "Description" ""
			(at 219.71 86.36 0)
			(effects
				(font
					(size 1.27 1.27)
				)
				(hide yes)
			)
		)
		(property "Author" "Antmicro"
			(at 234.95 93.98 0)
			(effects
				(font
					(size 1.27 1.27)
					(thickness 0.15)
				)
				(justify left bottom)
				(hide yes)
			)
		)
		(property "License" "Apache-2.0"
			(at 234.95 96.52 0)
			(effects
				(font
					(size 1.27 1.27)
					(thickness 0.15)
				)
				(justify left bottom)
				(hide yes)
			)
		)
		(pin "1"
		)
		(instances
			(project "com-express-7-baseboard"
				(path ""
					(reference "#PWR073")
					(unit 1)
				)
			)
		)
	)
	(symbol
		(lib_id "antmicropower:PWR_FLAG")
		(at 214.63 88.9 0)
		(unit 1)
		(exclude_from_sim no)
		(in_bom yes)
		(on_board yes)
		(dnp no)
		(property "Reference" "#FLG04"
			(at 214.63 86.995 0)
			(effects
				(font
					(size 1.27 1.27)
				)
				(hide yes)
			)
		)
		(property "Value" "PWR_FLAG"
			(at 208.28 85.09 0)
			(effects
				(font
					(size 1.27 1.27)
				)
				(justify left)
			)
		)
		(property "Footprint" ""
			(at 214.63 88.9 0)
			(effects
				(font
					(size 1.27 1.27)
				)
				(hide yes)
			)
		)
		(property "Datasheet" ""
			(at 214.63 88.9 0)
			(effects
				(font
					(size 1.27 1.27)
				)
				(hide yes)
			)
		)
		(property "Description" ""
			(at 214.63 88.9 0)
			(effects
				(font
					(size 1.27 1.27)
				)
				(hide yes)
			)
		)
		(pin "1"
		)
		(instances
			(project "com-express-7-baseboard"
				(path ""
					(reference "#FLG04")
					(unit 1)
				)
			)
		)
	)
	(symbol
		(lib_id "antmicroTVSDiodes:ESD204DQAR")
		(at 287.02 134.62 0)
		(unit 1)
		(exclude_from_sim no)
		(in_bom yes)
		(on_board yes)
		(dnp no)
		(fields_autoplaced yes)
		(property "Reference" "U8"
			(at 297.18 138.43 0)
			(effects
				(font
					(size 1.27 1.27)
					(thickness 0.15)
				)
				(justify left)
			)
		)
		(property "Value" "ESD204DQAR"
			(at 311.15 139.7 0)
			(effects
				(font
					(size 1.27 1.27)
					(thickness 0.15)
				)
				(justify left bottom)
				(hide yes)
			)
		)
		(property "Footprint" "antmicro-footprints:USON-10_2.5x1mm_P0.5mm"
			(at 311.15 142.24 0)
			(effects
				(font
					(size 1.27 1.27)
					(thickness 0.15)
				)
				(justify left bottom)
				(hide yes)
			)
		)
		(property "Datasheet" "https://www.ti.com/lit/ds/symlink/esd204.pdf?ts=1706004844383&ref_url=https%253A%252F%252Fwww.ti.com%252Finterface%252Fdiodes%252Fesd-protection-diodes%252Fproducts.html"
			(at 311.15 144.78 0)
			(effects
				(font
					(size 1.27 1.27)
					(thickness 0.15)
				)
				(justify left bottom)
				(hide yes)
			)
		)
		(property "Description" ""
			(at 287.02 134.62 0)
			(effects
				(font
					(size 1.27 1.27)
				)
				(hide yes)
			)
		)
		(property "MPN" "ESD204DQAR"
			(at 297.18 140.97 0)
			(effects
				(font
					(size 1.27 1.27)
					(thickness 0.15)
				)
				(justify left)
			)
		)
		(property "Manufacturer" "Texas Instruments"
			(at 311.15 147.32 0)
			(effects
				(font
					(size 1.27 1.27)
					(thickness 0.15)
				)
				(justify left bottom)
				(hide yes)
			)
		)
		(property "Author" "Antmicro"
			(at 311.15 149.86 0)
			(effects
				(font
					(size 1.27 1.27)
					(thickness 0.15)
				)
				(justify left bottom)
				(hide yes)
			)
		)
		(property "License" "Apache-2.0"
			(at 311.15 152.4 0)
			(effects
				(font
					(size 1.27 1.27)
					(thickness 0.15)
				)
				(justify left bottom)
				(hide yes)
			)
		)
		(pin "1"
		)
		(pin "4"
		)
		(pin "8"
		)
		(pin "9"
		)
		(pin "7"
		)
		(pin "5"
		)
		(pin "3"
		)
		(pin "2"
		)
		(pin "10"
		)
		(pin "6"
		)
		(instances
			(project "com-express-7-baseboard"
				(path ""
					(reference "U8")
					(unit 1)
				)
			)
		)
	)
	(symbol
		(lib_id "antmicropower:GND")
		(at 285.75 146.05 0)
		(unit 1)
		(exclude_from_sim no)
		(in_bom yes)
		(on_board yes)
		(dnp no)
		(property "Reference" "#PWR076"
			(at 294.64 148.59 0)
			(effects
				(font
					(size 1.27 1.27)
					(thickness 0.15)
				)
				(justify left bottom)
				(hide yes)
			)
		)
		(property "Value" "GND"
			(at 285.75 149.86 0)
			(effects
				(font
					(size 1.27 1.27)
					(thickness 0.15)
				)
			)
		)
		(property "Footprint" ""
			(at 294.64 153.67 0)
			(effects
				(font
					(size 1.27 1.27)
					(thickness 0.15)
				)
				(justify left bottom)
				(hide yes)
			)
		)
		(property "Datasheet" ""
			(at 294.64 158.75 0)
			(effects
				(font
					(size 1.27 1.27)
					(thickness 0.15)
				)
				(justify left bottom)
				(hide yes)
			)
		)
		(property "Description" ""
			(at 285.75 146.05 0)
			(effects
				(font
					(size 1.27 1.27)
				)
				(hide yes)
			)
		)
		(property "Author" "Antmicro"
			(at 294.64 153.67 0)
			(effects
				(font
					(size 1.27 1.27)
					(thickness 0.15)
				)
				(justify left bottom)
				(hide yes)
			)
		)
		(property "License" "Apache-2.0"
			(at 294.64 156.21 0)
			(effects
				(font
					(size 1.27 1.27)
					(thickness 0.15)
				)
				(justify left bottom)
				(hide yes)
			)
		)
		(pin "1"
		)
		(instances
			(project "com-express-7-baseboard"
				(path ""
					(reference "#PWR076")
					(unit 1)
				)
			)
		)
	)
	(symbol
		(lib_id "antmicroCapacitors0603:C_22u_16V_0603")
		(at 218.44 99.06 90)
		(unit 1)
		(exclude_from_sim no)
		(in_bom yes)
		(on_board yes)
		(dnp no)
		(property "Reference" "C37"
			(at 219.075 94.615 90)
			(effects
				(font
					(size 1.27 1.27)
					(thickness 0.15)
				)
				(justify right)
			)
		)
		(property "Value" "C_22u_16V_0603"
			(at 228.6 78.74 0)
			(effects
				(font
					(size 1.27 1.27)
					(thickness 0.15)
				)
				(justify left bottom)
				(hide yes)
			)
		)
		(property "Footprint" "antmicro-footprints:C_0603_1608Metric"
			(at 231.14 78.74 0)
			(effects
				(font
					(size 1.27 1.27)
					(thickness 0.15)
				)
				(justify left bottom)
				(hide yes)
			)
		)
		(property "Datasheet" "https://product.samsungsem.com/mlcc/CL10A226MO7JZN.do"
			(at 233.68 78.74 0)
			(effects
				(font
					(size 1.27 1.27)
					(thickness 0.15)
				)
				(justify left bottom)
				(hide yes)
			)
		)
		(property "Description" ""
			(at 218.44 99.06 0)
			(effects
				(font
					(size 1.27 1.27)
				)
				(hide yes)
			)
		)
		(property "MPN" "CL10A226MO7JZNC"
			(at 236.22 78.74 0)
			(effects
				(font
					(size 1.27 1.27)
					(thickness 0.15)
				)
				(justify left bottom)
				(hide yes)
			)
		)
		(property "Manufacturer" "Samsung Electro-Mechanics"
			(at 238.76 78.74 0)
			(effects
				(font
					(size 1.27 1.27)
					(thickness 0.15)
				)
				(justify left bottom)
				(hide yes)
			)
		)
		(property "License" "Apache-2.0"
			(at 241.3 78.74 0)
			(effects
				(font
					(size 1.27 1.27)
					(thickness 0.15)
				)
				(justify left bottom)
				(hide yes)
			)
		)
		(property "Author" "Antmicro"
			(at 243.84 78.74 0)
			(effects
				(font
					(size 1.27 1.27)
					(thickness 0.15)
				)
				(justify left bottom)
				(hide yes)
			)
		)
		(property "Val" "22u"
			(at 222.25 97.79 90)
			(effects
				(font
					(size 1.27 1.27)
					(thickness 0.15)
				)
				(justify left bottom)
			)
		)
		(property "Voltage" "16V"
			(at 246.38 78.74 0)
			(effects
				(font
					(size 1.27 1.27)
				)
				(justify left bottom)
				(hide yes)
			)
		)
		(property "Dielectric" ""
			(at 248.92 78.74 0)
			(effects
				(font
					(size 1.27 1.27)
				)
				(justify left bottom)
				(hide yes)
			)
		)
		(property "Public" "False"
			(at 251.46 78.74 0)
			(effects
				(font
					(size 1.27 1.27)
				)
				(justify left bottom)
				(hide yes)
			)
		)
		(pin "1"
		)
		(pin "2"
		)
		(instances
			(project "com-express-7-baseboard"
				(path ""
					(reference "C37")
					(unit 1)
				)
			)
		)
	)
	(symbol
		(lib_id "antmicropower:PWR_FLAG")
		(at 215.9 104.14 90)
		(unit 1)
		(exclude_from_sim no)
		(in_bom yes)
		(on_board yes)
		(dnp no)
		(property "Reference" "#FLG03"
			(at 213.995 104.14 0)
			(effects
				(font
					(size 1.27 1.27)
				)
				(hide yes)
			)
		)
		(property "Value" "PWR_FLAG"
			(at 213.36 105.41 90)
			(effects
				(font
					(size 1.27 1.27)
				)
				(justify left)
			)
		)
		(property "Footprint" ""
			(at 215.9 104.14 0)
			(effects
				(font
					(size 1.27 1.27)
				)
				(hide yes)
			)
		)
		(property "Datasheet" ""
			(at 215.9 104.14 0)
			(effects
				(font
					(size 1.27 1.27)
				)
				(hide yes)
			)
		)
		(property "Description" ""
			(at 215.9 104.14 0)
			(effects
				(font
					(size 1.27 1.27)
				)
				(hide yes)
			)
		)
		(pin "1"
		)
		(instances
			(project "com-express-7-baseboard"
				(path ""
					(reference "#FLG03")
					(unit 1)
				)
			)
		)
	)
	(symbol
		(lib_id "antmicroTVSDiodes:ESD204DQAR")
		(at 287.02 153.67 0)
		(unit 1)
		(exclude_from_sim no)
		(in_bom yes)
		(on_board yes)
		(dnp no)
		(fields_autoplaced yes)
		(property "Reference" "U9"
			(at 297.18 157.48 0)
			(effects
				(font
					(size 1.27 1.27)
					(thickness 0.15)
				)
				(justify left)
			)
		)
		(property "Value" "ESD204DQAR"
			(at 311.15 158.75 0)
			(effects
				(font
					(size 1.27 1.27)
					(thickness 0.15)
				)
				(justify left bottom)
				(hide yes)
			)
		)
		(property "Footprint" "antmicro-footprints:USON-10_2.5x1mm_P0.5mm"
			(at 311.15 161.29 0)
			(effects
				(font
					(size 1.27 1.27)
					(thickness 0.15)
				)
				(justify left bottom)
				(hide yes)
			)
		)
		(property "Datasheet" "https://www.ti.com/lit/ds/symlink/esd204.pdf?ts=1706004844383&ref_url=https%253A%252F%252Fwww.ti.com%252Finterface%252Fdiodes%252Fesd-protection-diodes%252Fproducts.html"
			(at 311.15 163.83 0)
			(effects
				(font
					(size 1.27 1.27)
					(thickness 0.15)
				)
				(justify left bottom)
				(hide yes)
			)
		)
		(property "Description" ""
			(at 287.02 153.67 0)
			(effects
				(font
					(size 1.27 1.27)
				)
				(hide yes)
			)
		)
		(property "MPN" "ESD204DQAR"
			(at 297.18 160.02 0)
			(effects
				(font
					(size 1.27 1.27)
					(thickness 0.15)
				)
				(justify left)
			)
		)
		(property "Manufacturer" "Texas Instruments"
			(at 311.15 166.37 0)
			(effects
				(font
					(size 1.27 1.27)
					(thickness 0.15)
				)
				(justify left bottom)
				(hide yes)
			)
		)
		(property "Author" "Antmicro"
			(at 311.15 168.91 0)
			(effects
				(font
					(size 1.27 1.27)
					(thickness 0.15)
				)
				(justify left bottom)
				(hide yes)
			)
		)
		(property "License" "Apache-2.0"
			(at 311.15 171.45 0)
			(effects
				(font
					(size 1.27 1.27)
					(thickness 0.15)
				)
				(justify left bottom)
				(hide yes)
			)
		)
		(pin "1"
		)
		(pin "4"
		)
		(pin "8"
		)
		(pin "9"
		)
		(pin "7"
		)
		(pin "5"
		)
		(pin "3"
		)
		(pin "2"
		)
		(pin "10"
		)
		(pin "6"
		)
		(instances
			(project "com-express-7-baseboard"
				(path ""
					(reference "U9")
					(unit 1)
				)
			)
		)
	)
	(symbol
		(lib_id "antmicroResistors0402:R_0R_0402")
		(at 219.71 109.22 0)
		(unit 1)
		(exclude_from_sim no)
		(in_bom yes)
		(on_board yes)
		(dnp no)
		(property "Reference" "R83"
			(at 227.33 107.95 0)
			(effects
				(font
					(size 1.27 1.27)
					(thickness 0.15)
				)
			)
		)
		(property "Value" "R_0R_0402"
			(at 240.03 121.92 0)
			(effects
				(font
					(size 1.27 1.27)
					(thickness 0.15)
				)
				(justify left bottom)
				(hide yes)
			)
		)
		(property "Footprint" "antmicro-footprints:R_0402_1005Metric"
			(at 240.03 124.46 0)
			(effects
				(font
					(size 1.27 1.27)
					(thickness 0.15)
				)
				(justify left bottom)
				(hide yes)
			)
		)
		(property "Datasheet" "https://industrial.panasonic.com/cdbs/www-data/pdf/RDA0000/AOA0000C301.pdf"
			(at 240.03 127 0)
			(effects
				(font
					(size 1.27 1.27)
					(thickness 0.15)
				)
				(justify left bottom)
				(hide yes)
			)
		)
		(property "Description" ""
			(at 219.71 109.22 0)
			(effects
				(font
					(size 1.27 1.27)
				)
				(hide yes)
			)
		)
		(property "MPN" "ERJ2GE0R00X"
			(at 240.03 129.54 0)
			(effects
				(font
					(size 1.27 1.27)
					(thickness 0.15)
				)
				(justify left bottom)
				(hide yes)
			)
		)
		(property "Manufacturer" "Panasonic"
			(at 240.03 132.08 0)
			(effects
				(font
					(size 1.27 1.27)
					(thickness 0.15)
				)
				(justify left bottom)
				(hide yes)
			)
		)
		(property "License" "Apache-2.0"
			(at 240.03 134.62 0)
			(effects
				(font
					(size 1.27 1.27)
					(thickness 0.15)
				)
				(justify left bottom)
				(hide yes)
			)
		)
		(property "Author" "Antmicro"
			(at 240.03 137.16 0)
			(effects
				(font
					(size 1.27 1.27)
					(thickness 0.15)
				)
				(justify left bottom)
				(hide yes)
			)
		)
		(property "Val" "0R"
			(at 218.44 107.95 0)
			(effects
				(font
					(size 1.27 1.27)
					(thickness 0.15)
				)
			)
		)
		(property "Tolerance" "~"
			(at 240.03 119.38 0)
			(effects
				(font
					(size 1.27 1.27)
				)
				(justify left bottom)
				(hide yes)
			)
		)
		(property "Current" "1A"
			(at 240.03 139.7 0)
			(effects
				(font
					(size 1.27 1.27)
					(thickness 0.15)
				)
				(justify left bottom)
				(hide yes)
			)
		)
		(property "Public" "False"
			(at 240.03 139.7 0)
			(effects
				(font
					(size 1.27 1.27)
				)
				(justify left bottom)
				(hide yes)
			)
		)
		(pin "2"
		)
		(pin "1"
		)
		(instances
			(project "com-express-7-baseboard"
				(path ""
					(reference "R83")
					(unit 1)
				)
			)
		)
	)
	(symbol
		(lib_id "antmicroResistors0402:R_10k_0402")
		(at 198.12 105.41 90)
		(unit 1)
		(exclude_from_sim no)
		(in_bom yes)
		(on_board yes)
		(dnp no)
		(property "Reference" "R79"
			(at 199.39 101.6 90)
			(effects
				(font
					(size 1.27 1.27)
					(thickness 0.15)
				)
				(justify right)
			)
		)
		(property "Value" "R_10k_0402"
			(at 210.82 85.09 0)
			(effects
				(font
					(size 1.27 1.27)
					(thickness 0.15)
				)
				(justify left bottom)
				(hide yes)
			)
		)
		(property "Footprint" "antmicro-footprints:R_0402_1005Metric"
			(at 213.36 85.09 0)
			(effects
				(font
					(size 1.27 1.27)
					(thickness 0.15)
				)
				(justify left bottom)
				(hide yes)
			)
		)
		(property "Datasheet" "https://www.bourns.com/docs/product-datasheets/cr.pdf"
			(at 215.9 85.09 0)
			(effects
				(font
					(size 1.27 1.27)
					(thickness 0.15)
				)
				(justify left bottom)
				(hide yes)
			)
		)
		(property "Description" ""
			(at 198.12 105.41 0)
			(effects
				(font
					(size 1.27 1.27)
				)
				(hide yes)
			)
		)
		(property "MPN" "CR0402-FX-1002GLF"
			(at 218.44 85.09 0)
			(effects
				(font
					(size 1.27 1.27)
					(thickness 0.15)
				)
				(justify left bottom)
				(hide yes)
			)
		)
		(property "Manufacturer" "Bourns"
			(at 220.98 85.09 0)
			(effects
				(font
					(size 1.27 1.27)
					(thickness 0.15)
				)
				(justify left bottom)
				(hide yes)
			)
		)
		(property "License" "Apache-2.0"
			(at 223.52 85.09 0)
			(effects
				(font
					(size 1.27 1.27)
					(thickness 0.15)
				)
				(justify left bottom)
				(hide yes)
			)
		)
		(property "Author" "Antmicro"
			(at 226.06 85.09 0)
			(effects
				(font
					(size 1.27 1.27)
					(thickness 0.15)
				)
				(justify left bottom)
				(hide yes)
			)
		)
		(property "Val" "10k"
			(at 199.39 104.14 90)
			(effects
				(font
					(size 1.27 1.27)
					(thickness 0.15)
				)
				(justify right)
			)
		)
		(property "Tolerance" "1%"
			(at 208.28 85.09 0)
			(effects
				(font
					(size 1.27 1.27)
				)
				(justify left bottom)
				(hide yes)
			)
		)
		(property "Public" "False"
			(at 228.6 85.09 0)
			(effects
				(font
					(size 1.27 1.27)
				)
				(justify left bottom)
				(hide yes)
			)
		)
		(pin "2"
		)
		(pin "1"
		)
		(instances
			(project "com-express-7-baseboard"
				(path ""
					(reference "R79")
					(unit 1)
				)
			)
		)
	)
	(symbol
		(lib_id "antmicroResistors0402:R_0R_0402")
		(at 185.42 127 0)
		(unit 1)
		(exclude_from_sim no)
		(in_bom yes)
		(on_board yes)
		(dnp no)
		(property "Reference" "R77"
			(at 185.42 125.73 0)
			(effects
				(font
					(size 1.27 1.27)
					(thickness 0.15)
				)
				(justify right)
			)
		)
		(property "Value" "R_0R_0402"
			(at 205.74 139.7 0)
			(effects
				(font
					(size 1.27 1.27)
					(thickness 0.15)
				)
				(justify left bottom)
				(hide yes)
			)
		)
		(property "Footprint" "antmicro-footprints:R_0402_1005Metric"
			(at 205.74 142.24 0)
			(effects
				(font
					(size 1.27 1.27)
					(thickness 0.15)
				)
				(justify left bottom)
				(hide yes)
			)
		)
		(property "Datasheet" "https://industrial.panasonic.com/cdbs/www-data/pdf/RDA0000/AOA0000C301.pdf"
			(at 205.74 144.78 0)
			(effects
				(font
					(size 1.27 1.27)
					(thickness 0.15)
				)
				(justify left bottom)
				(hide yes)
			)
		)
		(property "Description" ""
			(at 185.42 127 0)
			(effects
				(font
					(size 1.27 1.27)
				)
				(hide yes)
			)
		)
		(property "MPN" "ERJ2GE0R00X"
			(at 205.74 147.32 0)
			(effects
				(font
					(size 1.27 1.27)
					(thickness 0.15)
				)
				(justify left bottom)
				(hide yes)
			)
		)
		(property "Manufacturer" "Panasonic"
			(at 205.74 149.86 0)
			(effects
				(font
					(size 1.27 1.27)
					(thickness 0.15)
				)
				(justify left bottom)
				(hide yes)
			)
		)
		(property "License" "Apache-2.0"
			(at 205.74 152.4 0)
			(effects
				(font
					(size 1.27 1.27)
					(thickness 0.15)
				)
				(justify left bottom)
				(hide yes)
			)
		)
		(property "Author" "Antmicro"
			(at 205.74 154.94 0)
			(effects
				(font
					(size 1.27 1.27)
					(thickness 0.15)
				)
				(justify left bottom)
				(hide yes)
			)
		)
		(property "Val" "0R"
			(at 191.77 125.73 0)
			(effects
				(font
					(size 1.27 1.27)
					(thickness 0.15)
				)
			)
		)
		(property "Tolerance" "~"
			(at 205.74 137.16 0)
			(effects
				(font
					(size 1.27 1.27)
				)
				(justify left bottom)
				(hide yes)
			)
		)
		(property "Current" "1A"
			(at 205.74 157.48 0)
			(effects
				(font
					(size 1.27 1.27)
					(thickness 0.15)
				)
				(justify left bottom)
				(hide yes)
			)
		)
		(property "Public" "False"
			(at 205.74 157.48 0)
			(effects
				(font
					(size 1.27 1.27)
				)
				(justify left bottom)
				(hide yes)
			)
		)
		(pin "1"
		)
		(pin "2"
		)
		(instances
			(project "com-express-7-baseboard"
				(path ""
					(reference "R77")
					(unit 1)
				)
			)
		)
	)
	(symbol
		(lib_id "antmicropower:GND")
		(at 372.11 165.1 0)
		(unit 1)
		(exclude_from_sim no)
		(in_bom yes)
		(on_board yes)
		(dnp no)
		(property "Reference" "#PWR0471"
			(at 381 167.64 0)
			(effects
				(font
					(size 1.27 1.27)
					(thickness 0.15)
				)
				(justify left bottom)
				(hide yes)
			)
		)
		(property "Value" "GND"
			(at 372.11 168.91 0)
			(effects
				(font
					(size 1.27 1.27)
					(thickness 0.15)
				)
			)
		)
		(property "Footprint" ""
			(at 381 172.72 0)
			(effects
				(font
					(size 1.27 1.27)
					(thickness 0.15)
				)
				(justify left bottom)
				(hide yes)
			)
		)
		(property "Datasheet" ""
			(at 381 177.8 0)
			(effects
				(font
					(size 1.27 1.27)
					(thickness 0.15)
				)
				(justify left bottom)
				(hide yes)
			)
		)
		(property "Description" ""
			(at 372.11 165.1 0)
			(effects
				(font
					(size 1.27 1.27)
				)
				(hide yes)
			)
		)
		(property "Author" "Antmicro"
			(at 381 172.72 0)
			(effects
				(font
					(size 1.27 1.27)
					(thickness 0.15)
				)
				(justify left bottom)
				(hide yes)
			)
		)
		(property "License" "Apache-2.0"
			(at 381 175.26 0)
			(effects
				(font
					(size 1.27 1.27)
					(thickness 0.15)
				)
				(justify left bottom)
				(hide yes)
			)
		)
		(pin "1"
		)
		(instances
			(project "com-express-7-baseboard"
				(path ""
					(reference "#PWR0471")
					(unit 1)
				)
			)
		)
	)
	(symbol
		(lib_id "antmicroResistors0402:R_10k_0402")
		(at 194.31 105.41 90)
		(unit 1)
		(exclude_from_sim no)
		(in_bom yes)
		(on_board yes)
		(dnp yes)
		(fields_autoplaced yes)
		(property "Reference" "R78"
			(at 191.77 100.33 90)
			(effects
				(font
					(size 1.27 1.27)
					(thickness 0.15)
				)
				(justify left)
			)
		)
		(property "Value" "R_10k_0402"
			(at 207.01 85.09 0)
			(effects
				(font
					(size 1.27 1.27)
					(thickness 0.15)
				)
				(justify left bottom)
				(hide yes)
			)
		)
		(property "Footprint" "antmicro-footprints:R_0402_1005Metric"
			(at 209.55 85.09 0)
			(effects
				(font
					(size 1.27 1.27)
					(thickness 0.15)
				)
				(justify left bottom)
				(hide yes)
			)
		)
		(property "Datasheet" "https://www.bourns.com/docs/product-datasheets/cr.pdf"
			(at 212.09 85.09 0)
			(effects
				(font
					(size 1.27 1.27)
					(thickness 0.15)
				)
				(justify left bottom)
				(hide yes)
			)
		)
		(property "Description" ""
			(at 194.31 105.41 0)
			(effects
				(font
					(size 1.27 1.27)
				)
				(hide yes)
			)
		)
		(property "MPN" "CR0402-FX-1002GLF"
			(at 214.63 85.09 0)
			(effects
				(font
					(size 1.27 1.27)
					(thickness 0.15)
				)
				(justify left bottom)
				(hide yes)
			)
		)
		(property "Manufacturer" "Bourns"
			(at 217.17 85.09 0)
			(effects
				(font
					(size 1.27 1.27)
					(thickness 0.15)
				)
				(justify left bottom)
				(hide yes)
			)
		)
		(property "License" "Apache-2.0"
			(at 219.71 85.09 0)
			(effects
				(font
					(size 1.27 1.27)
					(thickness 0.15)
				)
				(justify left bottom)
				(hide yes)
			)
		)
		(property "Author" "Antmicro"
			(at 222.25 85.09 0)
			(effects
				(font
					(size 1.27 1.27)
					(thickness 0.15)
				)
				(justify left bottom)
				(hide yes)
			)
		)
		(property "Val" "10k"
			(at 191.77 102.87 90)
			(effects
				(font
					(size 1.27 1.27)
					(thickness 0.15)
				)
				(justify left)
			)
		)
		(property "Tolerance" "1%"
			(at 204.47 85.09 0)
			(effects
				(font
					(size 1.27 1.27)
				)
				(justify left bottom)
				(hide yes)
			)
		)
		(property "Public" "False"
			(at 224.79 85.09 0)
			(effects
				(font
					(size 1.27 1.27)
				)
				(justify left bottom)
				(hide yes)
			)
		)
		(pin "2"
		)
		(pin "1"
		)
		(instances
			(project "com-express-7-baseboard"
				(path ""
					(reference "R78")
					(unit 1)
				)
			)
		)
	)
	(symbol
		(lib_id "antmicroTVSDiodes:ESD204DQAR")
		(at 330.2 134.62 0)
		(unit 1)
		(exclude_from_sim no)
		(in_bom yes)
		(on_board yes)
		(dnp no)
		(fields_autoplaced yes)
		(property "Reference" "U10"
			(at 340.36 138.43 0)
			(effects
				(font
					(size 1.27 1.27)
					(thickness 0.15)
				)
				(justify left)
			)
		)
		(property "Value" "ESD204DQAR"
			(at 354.33 139.7 0)
			(effects
				(font
					(size 1.27 1.27)
					(thickness 0.15)
				)
				(justify left bottom)
				(hide yes)
			)
		)
		(property "Footprint" "antmicro-footprints:USON-10_2.5x1mm_P0.5mm"
			(at 354.33 142.24 0)
			(effects
				(font
					(size 1.27 1.27)
					(thickness 0.15)
				)
				(justify left bottom)
				(hide yes)
			)
		)
		(property "Datasheet" "https://www.ti.com/lit/ds/symlink/esd204.pdf?ts=1706004844383&ref_url=https%253A%252F%252Fwww.ti.com%252Finterface%252Fdiodes%252Fesd-protection-diodes%252Fproducts.html"
			(at 354.33 144.78 0)
			(effects
				(font
					(size 1.27 1.27)
					(thickness 0.15)
				)
				(justify left bottom)
				(hide yes)
			)
		)
		(property "Description" ""
			(at 330.2 134.62 0)
			(effects
				(font
					(size 1.27 1.27)
				)
				(hide yes)
			)
		)
		(property "MPN" "ESD204DQAR"
			(at 340.36 140.97 0)
			(effects
				(font
					(size 1.27 1.27)
					(thickness 0.15)
				)
				(justify left)
			)
		)
		(property "Manufacturer" "Texas Instruments"
			(at 354.33 147.32 0)
			(effects
				(font
					(size 1.27 1.27)
					(thickness 0.15)
				)
				(justify left bottom)
				(hide yes)
			)
		)
		(property "Author" "Antmicro"
			(at 354.33 149.86 0)
			(effects
				(font
					(size 1.27 1.27)
					(thickness 0.15)
				)
				(justify left bottom)
				(hide yes)
			)
		)
		(property "License" "Apache-2.0"
			(at 354.33 152.4 0)
			(effects
				(font
					(size 1.27 1.27)
					(thickness 0.15)
				)
				(justify left bottom)
				(hide yes)
			)
		)
		(pin "1"
		)
		(pin "4"
		)
		(pin "8"
		)
		(pin "9"
		)
		(pin "7"
		)
		(pin "5"
		)
		(pin "3"
		)
		(pin "2"
		)
		(pin "10"
		)
		(pin "6"
		)
		(instances
			(project "com-express-7-baseboard"
				(path ""
					(reference "U10")
					(unit 1)
				)
			)
		)
	)
	(symbol
		(lib_id "antmicropower:GND")
		(at 372.11 146.05 0)
		(unit 1)
		(exclude_from_sim no)
		(in_bom yes)
		(on_board yes)
		(dnp no)
		(property "Reference" "#PWR0470"
			(at 381 148.59 0)
			(effects
				(font
					(size 1.27 1.27)
					(thickness 0.15)
				)
				(justify left bottom)
				(hide yes)
			)
		)
		(property "Value" "GND"
			(at 372.11 149.86 0)
			(effects
				(font
					(size 1.27 1.27)
					(thickness 0.15)
				)
			)
		)
		(property "Footprint" ""
			(at 381 153.67 0)
			(effects
				(font
					(size 1.27 1.27)
					(thickness 0.15)
				)
				(justify left bottom)
				(hide yes)
			)
		)
		(property "Datasheet" ""
			(at 381 158.75 0)
			(effects
				(font
					(size 1.27 1.27)
					(thickness 0.15)
				)
				(justify left bottom)
				(hide yes)
			)
		)
		(property "Description" ""
			(at 372.11 146.05 0)
			(effects
				(font
					(size 1.27 1.27)
				)
				(hide yes)
			)
		)
		(property "Author" "Antmicro"
			(at 381 153.67 0)
			(effects
				(font
					(size 1.27 1.27)
					(thickness 0.15)
				)
				(justify left bottom)
				(hide yes)
			)
		)
		(property "License" "Apache-2.0"
			(at 381 156.21 0)
			(effects
				(font
					(size 1.27 1.27)
					(thickness 0.15)
				)
				(justify left bottom)
				(hide yes)
			)
		)
		(pin "1"
		)
		(instances
			(project "com-express-7-baseboard"
				(path ""
					(reference "#PWR0470")
					(unit 1)
				)
			)
		)
	)
	(symbol
		(lib_id "antmicroTVSDiodes:ESD204DQAR")
		(at 330.2 153.67 0)
		(unit 1)
		(exclude_from_sim no)
		(in_bom yes)
		(on_board yes)
		(dnp no)
		(fields_autoplaced yes)
		(property "Reference" "U11"
			(at 340.36 157.48 0)
			(effects
				(font
					(size 1.27 1.27)
					(thickness 0.15)
				)
				(justify left)
			)
		)
		(property "Value" "ESD204DQAR"
			(at 354.33 158.75 0)
			(effects
				(font
					(size 1.27 1.27)
					(thickness 0.15)
				)
				(justify left bottom)
				(hide yes)
			)
		)
		(property "Footprint" "antmicro-footprints:USON-10_2.5x1mm_P0.5mm"
			(at 354.33 161.29 0)
			(effects
				(font
					(size 1.27 1.27)
					(thickness 0.15)
				)
				(justify left bottom)
				(hide yes)
			)
		)
		(property "Datasheet" "https://www.ti.com/lit/ds/symlink/esd204.pdf?ts=1706004844383&ref_url=https%253A%252F%252Fwww.ti.com%252Finterface%252Fdiodes%252Fesd-protection-diodes%252Fproducts.html"
			(at 354.33 163.83 0)
			(effects
				(font
					(size 1.27 1.27)
					(thickness 0.15)
				)
				(justify left bottom)
				(hide yes)
			)
		)
		(property "Description" ""
			(at 330.2 153.67 0)
			(effects
				(font
					(size 1.27 1.27)
				)
				(hide yes)
			)
		)
		(property "MPN" "ESD204DQAR"
			(at 340.36 160.02 0)
			(effects
				(font
					(size 1.27 1.27)
					(thickness 0.15)
				)
				(justify left)
			)
		)
		(property "Manufacturer" "Texas Instruments"
			(at 354.33 166.37 0)
			(effects
				(font
					(size 1.27 1.27)
					(thickness 0.15)
				)
				(justify left bottom)
				(hide yes)
			)
		)
		(property "Author" "Antmicro"
			(at 354.33 168.91 0)
			(effects
				(font
					(size 1.27 1.27)
					(thickness 0.15)
				)
				(justify left bottom)
				(hide yes)
			)
		)
		(property "License" "Apache-2.0"
			(at 354.33 171.45 0)
			(effects
				(font
					(size 1.27 1.27)
					(thickness 0.15)
				)
				(justify left bottom)
				(hide yes)
			)
		)
		(pin "1"
		)
		(pin "4"
		)
		(pin "8"
		)
		(pin "9"
		)
		(pin "7"
		)
		(pin "5"
		)
		(pin "3"
		)
		(pin "2"
		)
		(pin "10"
		)
		(pin "6"
		)
		(instances
			(project "com-express-7-baseboard"
				(path ""
					(reference "U11")
					(unit 1)
				)
			)
		)
	)
	(symbol
		(lib_id "antmicroTVSDiodes:ESD204DQAR")
		(at 373.38 134.62 0)
		(unit 1)
		(exclude_from_sim no)
		(in_bom yes)
		(on_board yes)
		(dnp no)
		(fields_autoplaced yes)
		(property "Reference" "U17"
			(at 383.54 138.43 0)
			(effects
				(font
					(size 1.27 1.27)
					(thickness 0.15)
				)
				(justify left)
			)
		)
		(property "Value" "ESD204DQAR"
			(at 397.51 139.7 0)
			(effects
				(font
					(size 1.27 1.27)
					(thickness 0.15)
				)
				(justify left bottom)
				(hide yes)
			)
		)
		(property "Footprint" "antmicro-footprints:USON-10_2.5x1mm_P0.5mm"
			(at 397.51 142.24 0)
			(effects
				(font
					(size 1.27 1.27)
					(thickness 0.15)
				)
				(justify left bottom)
				(hide yes)
			)
		)
		(property "Datasheet" "https://www.ti.com/lit/ds/symlink/esd204.pdf?ts=1706004844383&ref_url=https%253A%252F%252Fwww.ti.com%252Finterface%252Fdiodes%252Fesd-protection-diodes%252Fproducts.html"
			(at 397.51 144.78 0)
			(effects
				(font
					(size 1.27 1.27)
					(thickness 0.15)
				)
				(justify left bottom)
				(hide yes)
			)
		)
		(property "Description" ""
			(at 373.38 134.62 0)
			(effects
				(font
					(size 1.27 1.27)
				)
				(hide yes)
			)
		)
		(property "MPN" "ESD204DQAR"
			(at 383.54 140.97 0)
			(effects
				(font
					(size 1.27 1.27)
					(thickness 0.15)
				)
				(justify left)
			)
		)
		(property "Manufacturer" "Texas Instruments"
			(at 397.51 147.32 0)
			(effects
				(font
					(size 1.27 1.27)
					(thickness 0.15)
				)
				(justify left bottom)
				(hide yes)
			)
		)
		(property "Author" "Antmicro"
			(at 397.51 149.86 0)
			(effects
				(font
					(size 1.27 1.27)
					(thickness 0.15)
				)
				(justify left bottom)
				(hide yes)
			)
		)
		(property "License" "Apache-2.0"
			(at 397.51 152.4 0)
			(effects
				(font
					(size 1.27 1.27)
					(thickness 0.15)
				)
				(justify left bottom)
				(hide yes)
			)
		)
		(pin "1"
		)
		(pin "4"
		)
		(pin "8"
		)
		(pin "9"
		)
		(pin "7"
		)
		(pin "5"
		)
		(pin "3"
		)
		(pin "2"
		)
		(pin "10"
		)
		(pin "6"
		)
		(instances
			(project "com-express-7-baseboard"
				(path ""
					(reference "U17")
					(unit 1)
				)
			)
		)
	)
	(symbol
		(lib_id "antmicropower:GND")
		(at 328.93 146.05 0)
		(unit 1)
		(exclude_from_sim no)
		(in_bom yes)
		(on_board yes)
		(dnp no)
		(property "Reference" "#PWR078"
			(at 337.82 148.59 0)
			(effects
				(font
					(size 1.27 1.27)
					(thickness 0.15)
				)
				(justify left bottom)
				(hide yes)
			)
		)
		(property "Value" "GND"
			(at 328.93 149.86 0)
			(effects
				(font
					(size 1.27 1.27)
					(thickness 0.15)
				)
			)
		)
		(property "Footprint" ""
			(at 337.82 153.67 0)
			(effects
				(font
					(size 1.27 1.27)
					(thickness 0.15)
				)
				(justify left bottom)
				(hide yes)
			)
		)
		(property "Datasheet" ""
			(at 337.82 158.75 0)
			(effects
				(font
					(size 1.27 1.27)
					(thickness 0.15)
				)
				(justify left bottom)
				(hide yes)
			)
		)
		(property "Description" ""
			(at 328.93 146.05 0)
			(effects
				(font
					(size 1.27 1.27)
				)
				(hide yes)
			)
		)
		(property "Author" "Antmicro"
			(at 337.82 153.67 0)
			(effects
				(font
					(size 1.27 1.27)
					(thickness 0.15)
				)
				(justify left bottom)
				(hide yes)
			)
		)
		(property "License" "Apache-2.0"
			(at 337.82 156.21 0)
			(effects
				(font
					(size 1.27 1.27)
					(thickness 0.15)
				)
				(justify left bottom)
				(hide yes)
			)
		)
		(pin "1"
		)
		(instances
			(project "com-express-7-baseboard"
				(path ""
					(reference "#PWR078")
					(unit 1)
				)
			)
		)
	)
	(symbol
		(lib_id "antmicroResistors0402:R_0R_0402")
		(at 219.71 111.76 0)
		(unit 1)
		(exclude_from_sim no)
		(in_bom yes)
		(on_board yes)
		(dnp no)
		(property "Reference" "R84"
			(at 227.33 110.49 0)
			(effects
				(font
					(size 1.27 1.27)
					(thickness 0.15)
				)
			)
		)
		(property "Value" "R_0R_0402"
			(at 240.03 124.46 0)
			(effects
				(font
					(size 1.27 1.27)
					(thickness 0.15)
				)
				(justify left bottom)
				(hide yes)
			)
		)
		(property "Footprint" "antmicro-footprints:R_0402_1005Metric"
			(at 240.03 127 0)
			(effects
				(font
					(size 1.27 1.27)
					(thickness 0.15)
				)
				(justify left bottom)
				(hide yes)
			)
		)
		(property "Datasheet" "https://industrial.panasonic.com/cdbs/www-data/pdf/RDA0000/AOA0000C301.pdf"
			(at 240.03 129.54 0)
			(effects
				(font
					(size 1.27 1.27)
					(thickness 0.15)
				)
				(justify left bottom)
				(hide yes)
			)
		)
		(property "Description" ""
			(at 219.71 111.76 0)
			(effects
				(font
					(size 1.27 1.27)
				)
				(hide yes)
			)
		)
		(property "MPN" "ERJ2GE0R00X"
			(at 240.03 132.08 0)
			(effects
				(font
					(size 1.27 1.27)
					(thickness 0.15)
				)
				(justify left bottom)
				(hide yes)
			)
		)
		(property "Manufacturer" "Panasonic"
			(at 240.03 134.62 0)
			(effects
				(font
					(size 1.27 1.27)
					(thickness 0.15)
				)
				(justify left bottom)
				(hide yes)
			)
		)
		(property "License" "Apache-2.0"
			(at 240.03 137.16 0)
			(effects
				(font
					(size 1.27 1.27)
					(thickness 0.15)
				)
				(justify left bottom)
				(hide yes)
			)
		)
		(property "Author" "Antmicro"
			(at 240.03 139.7 0)
			(effects
				(font
					(size 1.27 1.27)
					(thickness 0.15)
				)
				(justify left bottom)
				(hide yes)
			)
		)
		(property "Val" "0R"
			(at 218.44 110.49 0)
			(effects
				(font
					(size 1.27 1.27)
					(thickness 0.15)
				)
			)
		)
		(property "Tolerance" "~"
			(at 240.03 121.92 0)
			(effects
				(font
					(size 1.27 1.27)
				)
				(justify left bottom)
				(hide yes)
			)
		)
		(property "Current" "1A"
			(at 240.03 142.24 0)
			(effects
				(font
					(size 1.27 1.27)
					(thickness 0.15)
				)
				(justify left bottom)
				(hide yes)
			)
		)
		(property "Public" "False"
			(at 240.03 142.24 0)
			(effects
				(font
					(size 1.27 1.27)
				)
				(justify left bottom)
				(hide yes)
			)
		)
		(pin "2"
		)
		(pin "1"
		)
		(instances
			(project "com-express-7-baseboard"
				(path ""
					(reference "R84")
					(unit 1)
				)
			)
		)
	)
	(symbol
		(lib_id "antmicroTVSDiodes:ESD204DQAR")
		(at 373.38 153.67 0)
		(unit 1)
		(exclude_from_sim no)
		(in_bom yes)
		(on_board yes)
		(dnp no)
		(fields_autoplaced yes)
		(property "Reference" "U35"
			(at 383.54 157.48 0)
			(effects
				(font
					(size 1.27 1.27)
					(thickness 0.15)
				)
				(justify left)
			)
		)
		(property "Value" "ESD204DQAR"
			(at 397.51 158.75 0)
			(effects
				(font
					(size 1.27 1.27)
					(thickness 0.15)
				)
				(justify left bottom)
				(hide yes)
			)
		)
		(property "Footprint" "antmicro-footprints:USON-10_2.5x1mm_P0.5mm"
			(at 397.51 161.29 0)
			(effects
				(font
					(size 1.27 1.27)
					(thickness 0.15)
				)
				(justify left bottom)
				(hide yes)
			)
		)
		(property "Datasheet" "https://www.ti.com/lit/ds/symlink/esd204.pdf?ts=1706004844383&ref_url=https%253A%252F%252Fwww.ti.com%252Finterface%252Fdiodes%252Fesd-protection-diodes%252Fproducts.html"
			(at 397.51 163.83 0)
			(effects
				(font
					(size 1.27 1.27)
					(thickness 0.15)
				)
				(justify left bottom)
				(hide yes)
			)
		)
		(property "Description" ""
			(at 373.38 153.67 0)
			(effects
				(font
					(size 1.27 1.27)
				)
				(hide yes)
			)
		)
		(property "MPN" "ESD204DQAR"
			(at 383.54 160.02 0)
			(effects
				(font
					(size 1.27 1.27)
					(thickness 0.15)
				)
				(justify left)
			)
		)
		(property "Manufacturer" "Texas Instruments"
			(at 397.51 166.37 0)
			(effects
				(font
					(size 1.27 1.27)
					(thickness 0.15)
				)
				(justify left bottom)
				(hide yes)
			)
		)
		(property "Author" "Antmicro"
			(at 397.51 168.91 0)
			(effects
				(font
					(size 1.27 1.27)
					(thickness 0.15)
				)
				(justify left bottom)
				(hide yes)
			)
		)
		(property "License" "Apache-2.0"
			(at 397.51 171.45 0)
			(effects
				(font
					(size 1.27 1.27)
					(thickness 0.15)
				)
				(justify left bottom)
				(hide yes)
			)
		)
		(pin "1"
		)
		(pin "4"
		)
		(pin "8"
		)
		(pin "9"
		)
		(pin "7"
		)
		(pin "5"
		)
		(pin "3"
		)
		(pin "2"
		)
		(pin "10"
		)
		(pin "6"
		)
		(instances
			(project "com-express-7-baseboard"
				(path ""
					(reference "U35")
					(unit 1)
				)
			)
		)
	)
)
